FILE_TYPE = MACRO_DRAWING;
SET COLOR_WIRE YELLOW;
SET COLOR_PROP ORANGE;
SET COLOR_DOT WHITE;
SET COLOR_ARC YELLOW;
SET COLOR_BODY GREEN;
SET COLOR_NOTE PURPLE;
SET PROP_DISPLAY VALUE;
SET PAGE_NUMBER P67;
FORCEADD SOCKET4677_AZIF0045P001C01CS..26
(-650 1900);
FORCEPROP 1 LAST PART_NUMBER DGA^7000023
J 0
(-1700 4000);
DISPLAY 0.723404 (-1700 4000);
PAINT GREEN (-1700 4000);
DISPLAY INVISIBLE (-1700 4000);
FORCEPROP 2 LAST VALUE SOCKET4677_AZIF0045-P001C01CS
J 0
(-1700 4125);
DISPLAY 1.021277 (-1700 4125);
FORCEPROP 1 LAST MATERIAL IO
J 0
(-1700 3925);
DISPLAY 0.723404 (-1700 3925);
PAINT GREEN (-1700 3925);
FORCEPROP 2 LAST PART_TYPE SMLF
J 0
(-1700 4175);
DISPLAY 1.021277 (-1700 4175);
FORCEPROP 1 LAST $LOCATION U1
J 0
(-1700 4075);
DISPLAY 0.723404 (-1700 4075);
PAINT GREEN (-1700 4075);
FORCEPROP 0 LASTPIN (550 50) $PN BW80
J 0
(560 60);
DISPLAY 0.680851 (560 60);
PAINT MONO (560 60);
FORCEPROP 0 LASTPIN (550 100) $PN BW82
J 0
(560 110);
DISPLAY 0.680851 (560 110);
PAINT MONO (560 110);
FORCEPROP 0 LASTPIN (550 150) $PN BW84
J 0
(560 160);
DISPLAY 0.680851 (560 160);
PAINT MONO (560 160);
FORCEPROP 0 LASTPIN (550 200) $PN BW86
J 0
(560 210);
DISPLAY 0.680851 (560 210);
PAINT MONO (560 210);
FORCEPROP 0 LASTPIN (550 250) $PN BW88
J 0
(560 260);
DISPLAY 0.680851 (560 260);
PAINT MONO (560 260);
FORCEPROP 0 LASTPIN (550 300) $PN BW90
J 0
(560 310);
DISPLAY 0.680851 (560 310);
PAINT MONO (560 310);
FORCEPROP 0 LASTPIN (550 350) $PN BY32
J 0
(560 360);
DISPLAY 0.680851 (560 360);
PAINT MONO (560 360);
FORCEPROP 0 LASTPIN (550 400) $PN BY34
J 0
(560 410);
DISPLAY 0.680851 (560 410);
PAINT MONO (560 410);
FORCEPROP 0 LASTPIN (550 450) $PN BY36
J 0
(560 460);
DISPLAY 0.680851 (560 460);
PAINT MONO (560 460);
FORCEPROP 0 LASTPIN (550 500) $PN BY38
J 0
(560 510);
DISPLAY 0.680851 (560 510);
PAINT MONO (560 510);
FORCEPROP 0 LASTPIN (550 550) $PN BY40
J 0
(560 560);
DISPLAY 0.680851 (560 560);
PAINT MONO (560 560);
FORCEPROP 0 LASTPIN (550 600) $PN BY42
J 0
(560 610);
DISPLAY 0.680851 (560 610);
PAINT MONO (560 610);
FORCEPROP 0 LASTPIN (550 650) $PN BY44
J 0
(560 660);
DISPLAY 0.680851 (560 660);
PAINT MONO (560 660);
FORCEPROP 0 LASTPIN (550 700) $PN BY47
J 0
(560 710);
DISPLAY 0.680851 (560 710);
PAINT MONO (560 710);
FORCEPROP 0 LASTPIN (550 750) $PN BY49
J 0
(560 760);
DISPLAY 0.680851 (560 760);
PAINT MONO (560 760);
FORCEPROP 0 LASTPIN (550 800) $PN BY51
J 0
(560 810);
DISPLAY 0.680851 (560 810);
PAINT MONO (560 810);
FORCEPROP 0 LASTPIN (550 850) $PN BY53
J 0
(560 860);
DISPLAY 0.680851 (560 860);
PAINT MONO (560 860);
FORCEPROP 0 LASTPIN (550 900) $PN BY55
J 0
(560 910);
DISPLAY 0.680851 (560 910);
PAINT MONO (560 910);
FORCEPROP 0 LASTPIN (550 950) $PN BY57
J 0
(560 960);
DISPLAY 0.680851 (560 960);
PAINT MONO (560 960);
FORCEPROP 0 LASTPIN (550 1000) $PN BY59
J 0
(560 1010);
DISPLAY 0.680851 (560 1010);
PAINT MONO (560 1010);
FORCEPROP 0 LASTPIN (550 1050) $PN BY61
J 0
(560 1060);
DISPLAY 0.680851 (560 1060);
PAINT MONO (560 1060);
FORCEPROP 0 LASTPIN (550 1100) $PN BY63
J 0
(560 1110);
DISPLAY 0.680851 (560 1110);
PAINT MONO (560 1110);
FORCEPROP 0 LASTPIN (550 1150) $PN BY65
J 0
(560 1160);
DISPLAY 0.680851 (560 1160);
PAINT MONO (560 1160);
FORCEPROP 0 LASTPIN (550 1200) $PN BY67
J 0
(560 1210);
DISPLAY 0.680851 (560 1210);
PAINT MONO (560 1210);
FORCEPROP 0 LASTPIN (550 1250) $PN BY69
J 0
(560 1260);
DISPLAY 0.680851 (560 1260);
PAINT MONO (560 1260);
FORCEPROP 0 LASTPIN (550 1300) $PN BY71
J 0
(560 1310);
DISPLAY 0.680851 (560 1310);
PAINT MONO (560 1310);
FORCEPROP 0 LASTPIN (550 1350) $PN BY73
J 0
(560 1360);
DISPLAY 0.680851 (560 1360);
PAINT MONO (560 1360);
FORCEPROP 0 LASTPIN (550 1400) $PN BY75
J 0
(560 1410);
DISPLAY 0.680851 (560 1410);
PAINT MONO (560 1410);
FORCEPROP 0 LASTPIN (550 1450) $PN BY77
J 0
(560 1460);
DISPLAY 0.680851 (560 1460);
PAINT MONO (560 1460);
FORCEPROP 0 LASTPIN (550 1500) $PN BY79
J 0
(560 1510);
DISPLAY 0.680851 (560 1510);
PAINT MONO (560 1510);
FORCEPROP 0 LASTPIN (550 1550) $PN BY81
J 0
(560 1560);
DISPLAY 0.680851 (560 1560);
PAINT MONO (560 1560);
FORCEPROP 0 LASTPIN (550 1600) $PN BY83
J 0
(560 1610);
DISPLAY 0.680851 (560 1610);
PAINT MONO (560 1610);
FORCEPROP 0 LASTPIN (550 1650) $PN BY85
J 0
(560 1660);
DISPLAY 0.680851 (560 1660);
PAINT MONO (560 1660);
FORCEPROP 0 LASTPIN (550 1700) $PN BY87
J 0
(560 1710);
DISPLAY 0.680851 (560 1710);
PAINT MONO (560 1710);
FORCEPROP 0 LASTPIN (550 1750) $PN BY89
J 0
(560 1760);
DISPLAY 0.680851 (560 1760);
PAINT MONO (560 1760);
FORCEPROP 0 LASTPIN (550 1800) $PN CA33
J 0
(560 1810);
DISPLAY 0.680851 (560 1810);
PAINT MONO (560 1810);
FORCEPROP 0 LASTPIN (550 1850) $PN CA35
J 0
(560 1860);
DISPLAY 0.680851 (560 1860);
PAINT MONO (560 1860);
FORCEPROP 0 LASTPIN (550 1900) $PN CA37
J 0
(560 1910);
DISPLAY 0.680851 (560 1910);
PAINT MONO (560 1910);
FORCEPROP 0 LASTPIN (550 1950) $PN CA39
J 0
(560 1960);
DISPLAY 0.680851 (560 1960);
PAINT MONO (560 1960);
FORCEPROP 0 LASTPIN (550 2000) $PN CA41
J 0
(560 2010);
DISPLAY 0.680851 (560 2010);
PAINT MONO (560 2010);
FORCEPROP 0 LASTPIN (550 2050) $PN CA43
J 0
(560 2060);
DISPLAY 0.680851 (560 2060);
PAINT MONO (560 2060);
FORCEPROP 0 LASTPIN (550 2100) $PN CA45
J 0
(560 2110);
DISPLAY 0.680851 (560 2110);
PAINT MONO (560 2110);
FORCEPROP 0 LASTPIN (550 2150) $PN CA48
J 0
(560 2160);
DISPLAY 0.680851 (560 2160);
PAINT MONO (560 2160);
FORCEPROP 0 LASTPIN (550 2200) $PN CA50
J 0
(560 2210);
DISPLAY 0.680851 (560 2210);
PAINT MONO (560 2210);
FORCEPROP 0 LASTPIN (550 2250) $PN CA52
J 0
(560 2260);
DISPLAY 0.680851 (560 2260);
PAINT MONO (560 2260);
FORCEPROP 0 LASTPIN (550 2300) $PN CA54
J 0
(560 2310);
DISPLAY 0.680851 (560 2310);
PAINT MONO (560 2310);
FORCEPROP 0 LASTPIN (550 2350) $PN CA56
J 0
(560 2360);
DISPLAY 0.680851 (560 2360);
PAINT MONO (560 2360);
FORCEPROP 0 LASTPIN (550 2400) $PN CA58
J 0
(560 2410);
DISPLAY 0.680851 (560 2410);
PAINT MONO (560 2410);
FORCEPROP 0 LASTPIN (550 2450) $PN CA60
J 0
(560 2460);
DISPLAY 0.680851 (560 2460);
PAINT MONO (560 2460);
FORCEPROP 0 LASTPIN (550 2500) $PN CA62
J 0
(560 2510);
DISPLAY 0.680851 (560 2510);
PAINT MONO (560 2510);
FORCEPROP 0 LASTPIN (550 2550) $PN CA64
J 0
(560 2560);
DISPLAY 0.680851 (560 2560);
PAINT MONO (560 2560);
FORCEPROP 0 LASTPIN (550 2600) $PN CA66
J 0
(560 2610);
DISPLAY 0.680851 (560 2610);
PAINT MONO (560 2610);
FORCEPROP 0 LASTPIN (550 2650) $PN CA68
J 0
(560 2660);
DISPLAY 0.680851 (560 2660);
PAINT MONO (560 2660);
FORCEPROP 0 LASTPIN (550 2700) $PN CA70
J 0
(560 2710);
DISPLAY 0.680851 (560 2710);
PAINT MONO (560 2710);
FORCEPROP 0 LASTPIN (550 2750) $PN CA72
J 0
(560 2760);
DISPLAY 0.680851 (560 2760);
PAINT MONO (560 2760);
FORCEPROP 0 LASTPIN (550 2800) $PN CA74
J 0
(560 2810);
DISPLAY 0.680851 (560 2810);
PAINT MONO (560 2810);
FORCEPROP 0 LASTPIN (550 2850) $PN CA76
J 0
(560 2860);
DISPLAY 0.680851 (560 2860);
PAINT MONO (560 2860);
FORCEPROP 0 LASTPIN (550 2900) $PN CA78
J 0
(560 2910);
DISPLAY 0.680851 (560 2910);
PAINT MONO (560 2910);
FORCEPROP 0 LASTPIN (550 2950) $PN CA80
J 0
(560 2960);
DISPLAY 0.680851 (560 2960);
PAINT MONO (560 2960);
FORCEPROP 0 LASTPIN (550 3000) $PN CA82
J 0
(560 3010);
DISPLAY 0.680851 (560 3010);
PAINT MONO (560 3010);
FORCEPROP 0 LASTPIN (550 3050) $PN CA84
J 0
(560 3060);
DISPLAY 0.680851 (560 3060);
PAINT MONO (560 3060);
FORCEPROP 0 LASTPIN (550 3100) $PN CA86
J 0
(560 3110);
DISPLAY 0.680851 (560 3110);
PAINT MONO (560 3110);
FORCEPROP 0 LASTPIN (550 3150) $PN CA88
J 0
(560 3160);
DISPLAY 0.680851 (560 3160);
PAINT MONO (560 3160);
FORCEPROP 0 LASTPIN (550 3200) $PN CA90
J 0
(560 3210);
DISPLAY 0.680851 (560 3210);
PAINT MONO (560 3210);
FORCEPROP 0 LASTPIN (550 3250) $PN CB61
J 0
(560 3260);
DISPLAY 0.680851 (560 3260);
PAINT MONO (560 3260);
FORCEPROP 0 LASTPIN (550 3300) $PN CB75
J 0
(560 3310);
DISPLAY 0.680851 (560 3310);
PAINT MONO (560 3310);
FORCEPROP 0 LASTPIN (550 3350) $PN CB77
J 0
(560 3360);
DISPLAY 0.680851 (560 3360);
PAINT MONO (560 3360);
FORCEPROP 0 LASTPIN (550 3400) $PN CC33
J 0
(560 3410);
DISPLAY 0.680851 (560 3410);
PAINT MONO (560 3410);
FORCEPROP 0 LASTPIN (550 3450) $PN CC35
J 0
(560 3460);
DISPLAY 0.680851 (560 3460);
PAINT MONO (560 3460);
FORCEPROP 0 LASTPIN (550 3500) $PN CC37
J 0
(560 3510);
DISPLAY 0.680851 (560 3510);
PAINT MONO (560 3510);
FORCEPROP 0 LASTPIN (550 3550) $PN CC39
J 0
(560 3560);
DISPLAY 0.680851 (560 3560);
PAINT MONO (560 3560);
FORCEPROP 0 LASTPIN (550 3600) $PN CC41
J 0
(560 3610);
DISPLAY 0.680851 (560 3610);
PAINT MONO (560 3610);
FORCEPROP 0 LASTPIN (550 3650) $PN CC43
J 0
(560 3660);
DISPLAY 0.680851 (560 3660);
PAINT MONO (560 3660);
FORCEPROP 0 LASTPIN (550 3700) $PN CC45
J 0
(560 3710);
DISPLAY 0.680851 (560 3710);
PAINT MONO (560 3710);
FORCEPROP 0 LASTPIN (550 3750) $PN CC48
J 0
(560 3760);
DISPLAY 0.680851 (560 3760);
PAINT MONO (560 3760);
FORCEPROP 0 LASTPIN (-1850 50) $PN CC50
J 2
(-1860 60);
DISPLAY 0.680851 (-1860 60);
PAINT MONO (-1860 60);
FORCEPROP 0 LASTPIN (-1850 100) $PN CC52
J 2
(-1860 110);
DISPLAY 0.680851 (-1860 110);
PAINT MONO (-1860 110);
FORCEPROP 0 LASTPIN (-1850 150) $PN CC54
J 2
(-1860 160);
DISPLAY 0.680851 (-1860 160);
PAINT MONO (-1860 160);
FORCEPROP 0 LASTPIN (-1850 200) $PN CC56
J 2
(-1860 210);
DISPLAY 0.680851 (-1860 210);
PAINT MONO (-1860 210);
FORCEPROP 0 LASTPIN (-1850 250) $PN CC58
J 2
(-1860 260);
DISPLAY 0.680851 (-1860 260);
PAINT MONO (-1860 260);
FORCEPROP 0 LASTPIN (-1850 300) $PN CC60
J 2
(-1860 310);
DISPLAY 0.680851 (-1860 310);
PAINT MONO (-1860 310);
FORCEPROP 0 LASTPIN (-1850 350) $PN CC76
J 2
(-1860 360);
DISPLAY 0.680851 (-1860 360);
PAINT MONO (-1860 360);
FORCEPROP 0 LASTPIN (-1850 400) $PN CC78
J 2
(-1860 410);
DISPLAY 0.680851 (-1860 410);
PAINT MONO (-1860 410);
FORCEPROP 0 LASTPIN (-1850 450) $PN CC80
J 2
(-1860 460);
DISPLAY 0.680851 (-1860 460);
PAINT MONO (-1860 460);
FORCEPROP 0 LASTPIN (-1850 500) $PN CC82
J 2
(-1860 510);
DISPLAY 0.680851 (-1860 510);
PAINT MONO (-1860 510);
FORCEPROP 0 LASTPIN (-1850 550) $PN CC84
J 2
(-1860 560);
DISPLAY 0.680851 (-1860 560);
PAINT MONO (-1860 560);
FORCEPROP 0 LASTPIN (-1850 600) $PN CC86
J 2
(-1860 610);
DISPLAY 0.680851 (-1860 610);
PAINT MONO (-1860 610);
FORCEPROP 0 LASTPIN (-1850 650) $PN CC88
J 2
(-1860 660);
DISPLAY 0.680851 (-1860 660);
PAINT MONO (-1860 660);
FORCEPROP 0 LASTPIN (-1850 700) $PN CC90
J 2
(-1860 710);
DISPLAY 0.680851 (-1860 710);
PAINT MONO (-1860 710);
FORCEPROP 0 LASTPIN (-1850 750) $PN CD32
J 2
(-1860 760);
DISPLAY 0.680851 (-1860 760);
PAINT MONO (-1860 760);
FORCEPROP 0 LASTPIN (-1850 800) $PN CD34
J 2
(-1860 810);
DISPLAY 0.680851 (-1860 810);
PAINT MONO (-1860 810);
FORCEPROP 0 LASTPIN (-1850 850) $PN CD36
J 2
(-1860 860);
DISPLAY 0.680851 (-1860 860);
PAINT MONO (-1860 860);
FORCEPROP 0 LASTPIN (-1850 900) $PN CD38
J 2
(-1860 910);
DISPLAY 0.680851 (-1860 910);
PAINT MONO (-1860 910);
FORCEPROP 0 LASTPIN (-1850 950) $PN CD40
J 2
(-1860 960);
DISPLAY 0.680851 (-1860 960);
PAINT MONO (-1860 960);
FORCEPROP 0 LASTPIN (-1850 1000) $PN CD42
J 2
(-1860 1010);
DISPLAY 0.680851 (-1860 1010);
PAINT MONO (-1860 1010);
FORCEPROP 0 LASTPIN (-1850 1050) $PN CD44
J 2
(-1860 1060);
DISPLAY 0.680851 (-1860 1060);
PAINT MONO (-1860 1060);
FORCEPROP 0 LASTPIN (-1850 1100) $PN CD47
J 2
(-1860 1110);
DISPLAY 0.680851 (-1860 1110);
PAINT MONO (-1860 1110);
FORCEPROP 0 LASTPIN (-1850 1150) $PN CD49
J 2
(-1860 1160);
DISPLAY 0.680851 (-1860 1160);
PAINT MONO (-1860 1160);
FORCEPROP 0 LASTPIN (-1850 1200) $PN CD51
J 2
(-1860 1210);
DISPLAY 0.680851 (-1860 1210);
PAINT MONO (-1860 1210);
FORCEPROP 0 LASTPIN (-1850 1250) $PN CD53
J 2
(-1860 1260);
DISPLAY 0.680851 (-1860 1260);
PAINT MONO (-1860 1260);
FORCEPROP 0 LASTPIN (-1850 1300) $PN CD55
J 2
(-1860 1310);
DISPLAY 0.680851 (-1860 1310);
PAINT MONO (-1860 1310);
FORCEPROP 0 LASTPIN (-1850 1350) $PN CD57
J 2
(-1860 1360);
DISPLAY 0.680851 (-1860 1360);
PAINT MONO (-1860 1360);
FORCEPROP 0 LASTPIN (-1850 1400) $PN CD59
J 2
(-1860 1410);
DISPLAY 0.680851 (-1860 1410);
PAINT MONO (-1860 1410);
FORCEPROP 0 LASTPIN (-1850 1450) $PN CD79
J 2
(-1860 1460);
DISPLAY 0.680851 (-1860 1460);
PAINT MONO (-1860 1460);
FORCEPROP 0 LASTPIN (-1850 1500) $PN CD81
J 2
(-1860 1510);
DISPLAY 0.680851 (-1860 1510);
PAINT MONO (-1860 1510);
FORCEPROP 0 LASTPIN (-1850 1550) $PN CD83
J 2
(-1860 1560);
DISPLAY 0.680851 (-1860 1560);
PAINT MONO (-1860 1560);
FORCEPROP 0 LASTPIN (-1850 1600) $PN CD85
J 2
(-1860 1610);
DISPLAY 0.680851 (-1860 1610);
PAINT MONO (-1860 1610);
FORCEPROP 0 LASTPIN (-1850 1650) $PN CD87
J 2
(-1860 1660);
DISPLAY 0.680851 (-1860 1660);
PAINT MONO (-1860 1660);
FORCEPROP 0 LASTPIN (-1850 1700) $PN CD89
J 2
(-1860 1710);
DISPLAY 0.680851 (-1860 1710);
PAINT MONO (-1860 1710);
FORCEPROP 0 LASTPIN (-1850 1750) $PN CE80
J 2
(-1860 1760);
DISPLAY 0.680851 (-1860 1760);
PAINT MONO (-1860 1760);
FORCEPROP 0 LASTPIN (-1850 1800) $PN CE82
J 2
(-1860 1810);
DISPLAY 0.680851 (-1860 1810);
PAINT MONO (-1860 1810);
FORCEPROP 0 LASTPIN (-1850 1850) $PN CE84
J 2
(-1860 1860);
DISPLAY 0.680851 (-1860 1860);
PAINT MONO (-1860 1860);
FORCEPROP 0 LASTPIN (-1850 1900) $PN CE86
J 2
(-1860 1910);
DISPLAY 0.680851 (-1860 1910);
PAINT MONO (-1860 1910);
FORCEPROP 0 LASTPIN (-1850 1950) $PN CE88
J 2
(-1860 1960);
DISPLAY 0.680851 (-1860 1960);
PAINT MONO (-1860 1960);
FORCEPROP 0 LASTPIN (-1850 2000) $PN CE90
J 2
(-1860 2010);
DISPLAY 0.680851 (-1860 2010);
PAINT MONO (-1860 2010);
FORCEPROP 0 LASTPIN (-1850 2050) $PN CF79
J 2
(-1860 2060);
DISPLAY 0.680851 (-1860 2060);
PAINT MONO (-1860 2060);
FORCEPROP 0 LASTPIN (-1850 2100) $PN CF81
J 2
(-1860 2110);
DISPLAY 0.680851 (-1860 2110);
PAINT MONO (-1860 2110);
FORCEPROP 0 LASTPIN (-1850 2150) $PN CF83
J 2
(-1860 2160);
DISPLAY 0.680851 (-1860 2160);
PAINT MONO (-1860 2160);
FORCEPROP 0 LASTPIN (-1850 2200) $PN CF85
J 2
(-1860 2210);
DISPLAY 0.680851 (-1860 2210);
PAINT MONO (-1860 2210);
FORCEPROP 0 LASTPIN (-1850 2250) $PN CF87
J 2
(-1860 2260);
DISPLAY 0.680851 (-1860 2260);
PAINT MONO (-1860 2260);
FORCEPROP 0 LASTPIN (-1850 2300) $PN CF89
J 2
(-1860 2310);
DISPLAY 0.680851 (-1860 2310);
PAINT MONO (-1860 2310);
FORCEPROP 0 LASTPIN (-1850 2350) $PN CF91
J 2
(-1860 2360);
DISPLAY 0.680851 (-1860 2360);
PAINT MONO (-1860 2360);
FORCEPROP 0 LASTPIN (-1850 2400) $PN CG80
J 2
(-1860 2410);
DISPLAY 0.680851 (-1860 2410);
PAINT MONO (-1860 2410);
FORCEPROP 0 LASTPIN (-1850 2450) $PN CG82
J 2
(-1860 2460);
DISPLAY 0.680851 (-1860 2460);
PAINT MONO (-1860 2460);
FORCEPROP 0 LASTPIN (-1850 2500) $PN CG84
J 2
(-1860 2510);
DISPLAY 0.680851 (-1860 2510);
PAINT MONO (-1860 2510);
FORCEPROP 0 LASTPIN (-1850 2550) $PN CG86
J 2
(-1860 2560);
DISPLAY 0.680851 (-1860 2560);
PAINT MONO (-1860 2560);
FORCEPROP 0 LASTPIN (-1850 2600) $PN CG88
J 2
(-1860 2610);
DISPLAY 0.680851 (-1860 2610);
PAINT MONO (-1860 2610);
FORCEPROP 0 LASTPIN (-1850 2650) $PN CG90
J 2
(-1860 2660);
DISPLAY 0.680851 (-1860 2660);
PAINT MONO (-1860 2660);
FORCEPROP 0 LASTPIN (-1850 2700) $PN CH81
J 2
(-1860 2710);
DISPLAY 0.680851 (-1860 2710);
PAINT MONO (-1860 2710);
FORCEPROP 0 LASTPIN (-1850 2750) $PN CH91
J 2
(-1860 2760);
DISPLAY 0.680851 (-1860 2760);
PAINT MONO (-1860 2760);
FORCEPROP 0 LASTPIN (-1850 2800) $PN CJ82
J 2
(-1860 2810);
DISPLAY 0.680851 (-1860 2810);
PAINT MONO (-1860 2810);
FORCEPROP 0 LASTPIN (-1850 2850) $PN CJ84
J 2
(-1860 2860);
DISPLAY 0.680851 (-1860 2860);
PAINT MONO (-1860 2860);
FORCEPROP 0 LASTPIN (-1850 2900) $PN CJ86
J 2
(-1860 2910);
DISPLAY 0.680851 (-1860 2910);
PAINT MONO (-1860 2910);
FORCEPROP 0 LASTPIN (-1850 2950) $PN CJ88
J 2
(-1860 2960);
DISPLAY 0.680851 (-1860 2960);
PAINT MONO (-1860 2960);
FORCEPROP 0 LASTPIN (-1850 3000) $PN CJ90
J 2
(-1860 3010);
DISPLAY 0.680851 (-1860 3010);
PAINT MONO (-1860 3010);
FORCEPROP 0 LASTPIN (-1850 3050) $PN CK83
J 2
(-1860 3060);
DISPLAY 0.680851 (-1860 3060);
PAINT MONO (-1860 3060);
FORCEPROP 0 LASTPIN (-1850 3100) $PN CK85
J 2
(-1860 3110);
DISPLAY 0.680851 (-1860 3110);
PAINT MONO (-1860 3110);
FORCEPROP 0 LASTPIN (-1850 3150) $PN CK87
J 2
(-1860 3160);
DISPLAY 0.680851 (-1860 3160);
PAINT MONO (-1860 3160);
FORCEPROP 0 LASTPIN (-1850 3200) $PN CK89
J 2
(-1860 3210);
DISPLAY 0.680851 (-1860 3210);
PAINT MONO (-1860 3210);
FORCEPROP 0 LASTPIN (-1850 3250) $PN CK91
J 2
(-1860 3260);
DISPLAY 0.680851 (-1860 3260);
PAINT MONO (-1860 3260);
FORCEPROP 0 LASTPIN (-1850 3300) $PN CL84
J 2
(-1860 3310);
DISPLAY 0.680851 (-1860 3310);
PAINT MONO (-1860 3310);
FORCEPROP 0 LASTPIN (-1850 3350) $PN CL86
J 2
(-1860 3360);
DISPLAY 0.680851 (-1860 3360);
PAINT MONO (-1860 3360);
FORCEPROP 0 LASTPIN (-1850 3400) $PN CL88
J 2
(-1860 3410);
DISPLAY 0.680851 (-1860 3410);
PAINT MONO (-1860 3410);
FORCEPROP 0 LASTPIN (-1850 3450) $PN CL90
J 2
(-1860 3460);
DISPLAY 0.680851 (-1860 3460);
PAINT MONO (-1860 3460);
FORCEPROP 0 LASTPIN (-1850 3500) $PN CM87
J 2
(-1860 3510);
DISPLAY 0.680851 (-1860 3510);
PAINT MONO (-1860 3510);
FORCEPROP 0 LASTPIN (-1850 3600) $PN CM91
J 2
(-1860 3610);
DISPLAY 0.680851 (-1860 3610);
PAINT MONO (-1860 3610);
FORCEPROP 0 LASTPIN (-1850 3650) $PN CN88
J 2
(-1860 3660);
DISPLAY 0.680851 (-1860 3660);
PAINT MONO (-1860 3660);
FORCEPROP 0 LASTPIN (-1850 3700) $PN CN90
J 2
(-1860 3710);
DISPLAY 0.680851 (-1860 3710);
PAINT MONO (-1860 3710);
FORCEPROP 0 LASTPIN (-1850 3750) $PN CP89
J 2
(-1860 3760);
DISPLAY 0.680851 (-1860 3760);
PAINT MONO (-1860 3760);
FORCEPROP 0 LASTPIN (-1850 3550) $PN CM89
J 2
(-1860 3560);
DISPLAY 0.680851 (-1860 3560);
PAINT MONO (-1860 3560);
FORCEPROP 1 LAST CDS_LMAN_SYM_OUTLINE -1050,2000,1050,-2000
J 0
(-650 1900);
DISPLAY 0.468085 (-650 1900);
PAINT GREEN (-650 1900);
DISPLAY INVISIBLE (-650 1900);
FORCEPROP 1 LAST NEEDS_NO_SIZE TRUE
J 0
(-650 1900);
DISPLAY 0.723404 (-650 1900);
PAINT GREEN (-650 1900);
DISPLAY INVISIBLE (-650 1900);
FORCEPROP 2 LAST CDS_LIB pure_quanta
J 0
(-650 1900);
DISPLAY INVISIBLE (-650 1900);
FORCEPROP 2 LAST CDS_LOCATION U1
J 0
(-1700 4225);
DISPLAY 1.021277 (-1700 4225);
DISPLAY INVISIBLE (-1700 4225);
FORCEPROP 0 LAST $SEC 26
J 0
(-1700 4225);
DISPLAY 0.680851 (-1700 4225);
PAINT MONO (-1700 4225);
DISPLAY INVISIBLE (-1700 4225);
FORCEPROP 2 LAST CDS_SEC 26
J 0
(-1700 4225);
DISPLAY 1.021277 (-1700 4225);
DISPLAY INVISIBLE (-1700 4225);
FORCEPROP 1 LAST PATH I1
J 0
(-650 1900);
DISPLAY 0.723404 (-650 1900);
PAINT GREEN (-650 1900);
DISPLAY INVISIBLE (-650 1900);
FORCEADD VCC_CORE..1
(-2100 3975);
FORCEPROP 3 LASTPIN (-2100 3925) SIG_NAME PVCCIN_CPU1\g
J 0
(-2090 3935);
DISPLAY 0.659574 (-2090 3935);
PAINT MONO (-2090 3935);
DISPLAY INVISIBLE (-2090 3935);
FORCEPROP 1 LAST HDL_POWER PVCCIN_CPU1
J 1
(-2100 4025);
DISPLAY 1.148936 (-2100 4025);
PAINT GREEN (-2100 4025);
FORCEPROP 2 LAST CDS_LIB logical_power
J 0
(-2100 3975);
PAINT MONO (-2100 3975);
DISPLAY INVISIBLE (-2100 3975);
FORCEPROP 1 LAST PATH I2
J 0
(-2050 4000);
DISPLAY 0.872340 (-2050 4000);
PAINT AQUA (-2050 4000);
DISPLAY INVISIBLE (-2050 4000);
FORCEADD SOCKET4677_AZIF0045P001C01CS..27
(3725 1900);
FORCEPROP 1 LAST PART_NUMBER DGA^7000023
J 0
(2675 4000);
DISPLAY 0.723404 (2675 4000);
PAINT GREEN (2675 4000);
DISPLAY INVISIBLE (2675 4000);
FORCEPROP 2 LAST VALUE SOCKET4677_AZIF0045-P001C01CS
J 0
(2675 4125);
DISPLAY 1.021277 (2675 4125);
FORCEPROP 1 LAST MATERIAL IO
J 0
(2675 3925);
DISPLAY 0.723404 (2675 3925);
PAINT GREEN (2675 3925);
FORCEPROP 2 LAST PART_TYPE SMLF
J 0
(2675 4175);
DISPLAY 1.021277 (2675 4175);
FORCEPROP 1 LAST $LOCATION U1
J 0
(2675 4075);
DISPLAY 0.723404 (2675 4075);
PAINT GREEN (2675 4075);
FORCEPROP 0 LASTPIN (4925 50) $PN BN43
J 0
(4935 60);
DISPLAY 0.680851 (4935 60);
PAINT MONO (4935 60);
FORCEPROP 0 LASTPIN (4925 100) $PN BN45
J 0
(4935 110);
DISPLAY 0.680851 (4935 110);
PAINT MONO (4935 110);
FORCEPROP 0 LASTPIN (4925 150) $PN BN48
J 0
(4935 160);
DISPLAY 0.680851 (4935 160);
PAINT MONO (4935 160);
FORCEPROP 0 LASTPIN (4925 200) $PN BN50
J 0
(4935 210);
DISPLAY 0.680851 (4935 210);
PAINT MONO (4935 210);
FORCEPROP 0 LASTPIN (4925 250) $PN BN52
J 0
(4935 260);
DISPLAY 0.680851 (4935 260);
PAINT MONO (4935 260);
FORCEPROP 0 LASTPIN (4925 300) $PN BN54
J 0
(4935 310);
DISPLAY 0.680851 (4935 310);
PAINT MONO (4935 310);
FORCEPROP 0 LASTPIN (4925 350) $PN BN56
J 0
(4935 360);
DISPLAY 0.680851 (4935 360);
PAINT MONO (4935 360);
FORCEPROP 0 LASTPIN (4925 400) $PN BN58
J 0
(4935 410);
DISPLAY 0.680851 (4935 410);
PAINT MONO (4935 410);
FORCEPROP 0 LASTPIN (4925 450) $PN BN60
J 0
(4935 460);
DISPLAY 0.680851 (4935 460);
PAINT MONO (4935 460);
FORCEPROP 0 LASTPIN (4925 500) $PN BN78
J 0
(4935 510);
DISPLAY 0.680851 (4935 510);
PAINT MONO (4935 510);
FORCEPROP 0 LASTPIN (4925 550) $PN BN80
J 0
(4935 560);
DISPLAY 0.680851 (4935 560);
PAINT MONO (4935 560);
FORCEPROP 0 LASTPIN (4925 600) $PN BN82
J 0
(4935 610);
DISPLAY 0.680851 (4935 610);
PAINT MONO (4935 610);
FORCEPROP 0 LASTPIN (4925 650) $PN BN84
J 0
(4935 660);
DISPLAY 0.680851 (4935 660);
PAINT MONO (4935 660);
FORCEPROP 0 LASTPIN (4925 700) $PN BN86
J 0
(4935 710);
DISPLAY 0.680851 (4935 710);
PAINT MONO (4935 710);
FORCEPROP 0 LASTPIN (4925 750) $PN BN88
J 0
(4935 760);
DISPLAY 0.680851 (4935 760);
PAINT MONO (4935 760);
FORCEPROP 0 LASTPIN (4925 800) $PN BN90
J 0
(4935 810);
DISPLAY 0.680851 (4935 810);
PAINT MONO (4935 810);
FORCEPROP 0 LASTPIN (4925 850) $PN BP32
J 0
(4935 860);
DISPLAY 0.680851 (4935 860);
PAINT MONO (4935 860);
FORCEPROP 0 LASTPIN (4925 900) $PN BP34
J 0
(4935 910);
DISPLAY 0.680851 (4935 910);
PAINT MONO (4935 910);
FORCEPROP 0 LASTPIN (4925 950) $PN BP36
J 0
(4935 960);
DISPLAY 0.680851 (4935 960);
PAINT MONO (4935 960);
FORCEPROP 0 LASTPIN (4925 1000) $PN BP38
J 0
(4935 1010);
DISPLAY 0.680851 (4935 1010);
PAINT MONO (4935 1010);
FORCEPROP 0 LASTPIN (4925 1050) $PN BP40
J 0
(4935 1060);
DISPLAY 0.680851 (4935 1060);
PAINT MONO (4935 1060);
FORCEPROP 0 LASTPIN (4925 1100) $PN BP42
J 0
(4935 1110);
DISPLAY 0.680851 (4935 1110);
PAINT MONO (4935 1110);
FORCEPROP 0 LASTPIN (4925 1150) $PN BP44
J 0
(4935 1160);
DISPLAY 0.680851 (4935 1160);
PAINT MONO (4935 1160);
FORCEPROP 0 LASTPIN (4925 1200) $PN BP47
J 0
(4935 1210);
DISPLAY 0.680851 (4935 1210);
PAINT MONO (4935 1210);
FORCEPROP 0 LASTPIN (4925 1250) $PN BP49
J 0
(4935 1260);
DISPLAY 0.680851 (4935 1260);
PAINT MONO (4935 1260);
FORCEPROP 0 LASTPIN (4925 1300) $PN BP51
J 0
(4935 1310);
DISPLAY 0.680851 (4935 1310);
PAINT MONO (4935 1310);
FORCEPROP 0 LASTPIN (4925 1350) $PN BP53
J 0
(4935 1360);
DISPLAY 0.680851 (4935 1360);
PAINT MONO (4935 1360);
FORCEPROP 0 LASTPIN (4925 1400) $PN BP55
J 0
(4935 1410);
DISPLAY 0.680851 (4935 1410);
PAINT MONO (4935 1410);
FORCEPROP 0 LASTPIN (4925 1450) $PN BP57
J 0
(4935 1460);
DISPLAY 0.680851 (4935 1460);
PAINT MONO (4935 1460);
FORCEPROP 0 LASTPIN (4925 1500) $PN BP59
J 0
(4935 1510);
DISPLAY 0.680851 (4935 1510);
PAINT MONO (4935 1510);
FORCEPROP 0 LASTPIN (4925 1550) $PN BP61
J 0
(4935 1560);
DISPLAY 0.680851 (4935 1560);
PAINT MONO (4935 1560);
FORCEPROP 0 LASTPIN (4925 1600) $PN BP79
J 0
(4935 1610);
DISPLAY 0.680851 (4935 1610);
PAINT MONO (4935 1610);
FORCEPROP 0 LASTPIN (4925 1650) $PN BP81
J 0
(4935 1660);
DISPLAY 0.680851 (4935 1660);
PAINT MONO (4935 1660);
FORCEPROP 0 LASTPIN (4925 1700) $PN BP83
J 0
(4935 1710);
DISPLAY 0.680851 (4935 1710);
PAINT MONO (4935 1710);
FORCEPROP 0 LASTPIN (4925 1750) $PN BP85
J 0
(4935 1760);
DISPLAY 0.680851 (4935 1760);
PAINT MONO (4935 1760);
FORCEPROP 0 LASTPIN (4925 1800) $PN BP87
J 0
(4935 1810);
DISPLAY 0.680851 (4935 1810);
PAINT MONO (4935 1810);
FORCEPROP 0 LASTPIN (4925 1850) $PN BP89
J 0
(4935 1860);
DISPLAY 0.680851 (4935 1860);
PAINT MONO (4935 1860);
FORCEPROP 0 LASTPIN (4925 1900) $PN BR60
J 0
(4935 1910);
DISPLAY 0.680851 (4935 1910);
PAINT MONO (4935 1910);
FORCEPROP 0 LASTPIN (4925 1950) $PN BR62
J 0
(4935 1960);
DISPLAY 0.680851 (4935 1960);
PAINT MONO (4935 1960);
FORCEPROP 0 LASTPIN (4925 2000) $PN BR78
J 0
(4935 2010);
DISPLAY 0.680851 (4935 2010);
PAINT MONO (4935 2010);
FORCEPROP 0 LASTPIN (4925 2050) $PN BT32
J 0
(4935 2060);
DISPLAY 0.680851 (4935 2060);
PAINT MONO (4935 2060);
FORCEPROP 0 LASTPIN (4925 2100) $PN BT34
J 0
(4935 2110);
DISPLAY 0.680851 (4935 2110);
PAINT MONO (4935 2110);
FORCEPROP 0 LASTPIN (4925 2150) $PN BT36
J 0
(4935 2160);
DISPLAY 0.680851 (4935 2160);
PAINT MONO (4935 2160);
FORCEPROP 0 LASTPIN (4925 2200) $PN BT38
J 0
(4935 2210);
DISPLAY 0.680851 (4935 2210);
PAINT MONO (4935 2210);
FORCEPROP 0 LASTPIN (4925 2250) $PN BT40
J 0
(4935 2260);
DISPLAY 0.680851 (4935 2260);
PAINT MONO (4935 2260);
FORCEPROP 0 LASTPIN (4925 2300) $PN BT42
J 0
(4935 2310);
DISPLAY 0.680851 (4935 2310);
PAINT MONO (4935 2310);
FORCEPROP 0 LASTPIN (4925 2350) $PN BT44
J 0
(4935 2360);
DISPLAY 0.680851 (4935 2360);
PAINT MONO (4935 2360);
FORCEPROP 0 LASTPIN (4925 2400) $PN BT47
J 0
(4935 2410);
DISPLAY 0.680851 (4935 2410);
PAINT MONO (4935 2410);
FORCEPROP 0 LASTPIN (4925 2450) $PN BT49
J 0
(4935 2460);
DISPLAY 0.680851 (4935 2460);
PAINT MONO (4935 2460);
FORCEPROP 0 LASTPIN (4925 2500) $PN BT51
J 0
(4935 2510);
DISPLAY 0.680851 (4935 2510);
PAINT MONO (4935 2510);
FORCEPROP 0 LASTPIN (4925 2550) $PN BT53
J 0
(4935 2560);
DISPLAY 0.680851 (4935 2560);
PAINT MONO (4935 2560);
FORCEPROP 0 LASTPIN (4925 2600) $PN BT55
J 0
(4935 2610);
DISPLAY 0.680851 (4935 2610);
PAINT MONO (4935 2610);
FORCEPROP 0 LASTPIN (4925 2650) $PN BT57
J 0
(4935 2660);
DISPLAY 0.680851 (4935 2660);
PAINT MONO (4935 2660);
FORCEPROP 0 LASTPIN (4925 2700) $PN BT59
J 0
(4935 2710);
DISPLAY 0.680851 (4935 2710);
PAINT MONO (4935 2710);
FORCEPROP 0 LASTPIN (4925 2750) $PN BT61
J 0
(4935 2760);
DISPLAY 0.680851 (4935 2760);
PAINT MONO (4935 2760);
FORCEPROP 0 LASTPIN (4925 2800) $PN BT63
J 0
(4935 2810);
DISPLAY 0.680851 (4935 2810);
PAINT MONO (4935 2810);
FORCEPROP 0 LASTPIN (4925 2850) $PN BT65
J 0
(4935 2860);
DISPLAY 0.680851 (4935 2860);
PAINT MONO (4935 2860);
FORCEPROP 0 LASTPIN (4925 2900) $PN BT67
J 0
(4935 2910);
DISPLAY 0.680851 (4935 2910);
PAINT MONO (4935 2910);
FORCEPROP 0 LASTPIN (4925 2950) $PN BT69
J 0
(4935 2960);
DISPLAY 0.680851 (4935 2960);
PAINT MONO (4935 2960);
FORCEPROP 0 LASTPIN (4925 3000) $PN BT71
J 0
(4935 3010);
DISPLAY 0.680851 (4935 3010);
PAINT MONO (4935 3010);
FORCEPROP 0 LASTPIN (4925 3050) $PN BT73
J 0
(4935 3060);
DISPLAY 0.680851 (4935 3060);
PAINT MONO (4935 3060);
FORCEPROP 0 LASTPIN (4925 3100) $PN BT75
J 0
(4935 3110);
DISPLAY 0.680851 (4935 3110);
PAINT MONO (4935 3110);
FORCEPROP 0 LASTPIN (4925 3150) $PN BT77
J 0
(4935 3160);
DISPLAY 0.680851 (4935 3160);
PAINT MONO (4935 3160);
FORCEPROP 0 LASTPIN (4925 3200) $PN BT79
J 0
(4935 3210);
DISPLAY 0.680851 (4935 3210);
PAINT MONO (4935 3210);
FORCEPROP 0 LASTPIN (4925 3250) $PN BT81
J 0
(4935 3260);
DISPLAY 0.680851 (4935 3260);
PAINT MONO (4935 3260);
FORCEPROP 0 LASTPIN (4925 3300) $PN BT83
J 0
(4935 3310);
DISPLAY 0.680851 (4935 3310);
PAINT MONO (4935 3310);
FORCEPROP 0 LASTPIN (4925 3350) $PN BT85
J 0
(4935 3360);
DISPLAY 0.680851 (4935 3360);
PAINT MONO (4935 3360);
FORCEPROP 0 LASTPIN (4925 3400) $PN BT87
J 0
(4935 3410);
DISPLAY 0.680851 (4935 3410);
PAINT MONO (4935 3410);
FORCEPROP 0 LASTPIN (4925 3450) $PN BT89
J 0
(4935 3460);
DISPLAY 0.680851 (4935 3460);
PAINT MONO (4935 3460);
FORCEPROP 0 LASTPIN (4925 3500) $PN BU33
J 0
(4935 3510);
DISPLAY 0.680851 (4935 3510);
PAINT MONO (4935 3510);
FORCEPROP 0 LASTPIN (4925 3550) $PN BU35
J 0
(4935 3560);
DISPLAY 0.680851 (4935 3560);
PAINT MONO (4935 3560);
FORCEPROP 0 LASTPIN (4925 3600) $PN BU37
J 0
(4935 3610);
DISPLAY 0.680851 (4935 3610);
PAINT MONO (4935 3610);
FORCEPROP 0 LASTPIN (4925 3650) $PN BU39
J 0
(4935 3660);
DISPLAY 0.680851 (4935 3660);
PAINT MONO (4935 3660);
FORCEPROP 0 LASTPIN (4925 3700) $PN BU41
J 0
(4935 3710);
DISPLAY 0.680851 (4935 3710);
PAINT MONO (4935 3710);
FORCEPROP 0 LASTPIN (4925 3750) $PN BU43
J 0
(4935 3760);
DISPLAY 0.680851 (4935 3760);
PAINT MONO (4935 3760);
FORCEPROP 0 LASTPIN (2525 50) $PN BU45
J 2
(2515 60);
DISPLAY 0.680851 (2515 60);
PAINT MONO (2515 60);
FORCEPROP 0 LASTPIN (2525 100) $PN BU48
J 2
(2515 110);
DISPLAY 0.680851 (2515 110);
PAINT MONO (2515 110);
FORCEPROP 0 LASTPIN (2525 150) $PN BU50
J 2
(2515 160);
DISPLAY 0.680851 (2515 160);
PAINT MONO (2515 160);
FORCEPROP 0 LASTPIN (2525 200) $PN BU52
J 2
(2515 210);
DISPLAY 0.680851 (2515 210);
PAINT MONO (2515 210);
FORCEPROP 0 LASTPIN (2525 250) $PN BU54
J 2
(2515 260);
DISPLAY 0.680851 (2515 260);
PAINT MONO (2515 260);
FORCEPROP 0 LASTPIN (2525 300) $PN BU56
J 2
(2515 310);
DISPLAY 0.680851 (2515 310);
PAINT MONO (2515 310);
FORCEPROP 0 LASTPIN (2525 350) $PN BU58
J 2
(2515 360);
DISPLAY 0.680851 (2515 360);
PAINT MONO (2515 360);
FORCEPROP 0 LASTPIN (2525 400) $PN BU60
J 2
(2515 410);
DISPLAY 0.680851 (2515 410);
PAINT MONO (2515 410);
FORCEPROP 0 LASTPIN (2525 450) $PN BU62
J 2
(2515 460);
DISPLAY 0.680851 (2515 460);
PAINT MONO (2515 460);
FORCEPROP 0 LASTPIN (2525 500) $PN BU64
J 2
(2515 510);
DISPLAY 0.680851 (2515 510);
PAINT MONO (2515 510);
FORCEPROP 0 LASTPIN (2525 550) $PN BU66
J 2
(2515 560);
DISPLAY 0.680851 (2515 560);
PAINT MONO (2515 560);
FORCEPROP 0 LASTPIN (2525 600) $PN BU68
J 2
(2515 610);
DISPLAY 0.680851 (2515 610);
PAINT MONO (2515 610);
FORCEPROP 0 LASTPIN (2525 650) $PN BU70
J 2
(2515 660);
DISPLAY 0.680851 (2515 660);
PAINT MONO (2515 660);
FORCEPROP 0 LASTPIN (2525 700) $PN BU72
J 2
(2515 710);
DISPLAY 0.680851 (2515 710);
PAINT MONO (2515 710);
FORCEPROP 0 LASTPIN (2525 750) $PN BU74
J 2
(2515 760);
DISPLAY 0.680851 (2515 760);
PAINT MONO (2515 760);
FORCEPROP 0 LASTPIN (2525 800) $PN BU76
J 2
(2515 810);
DISPLAY 0.680851 (2515 810);
PAINT MONO (2515 810);
FORCEPROP 0 LASTPIN (2525 850) $PN BU78
J 2
(2515 860);
DISPLAY 0.680851 (2515 860);
PAINT MONO (2515 860);
FORCEPROP 0 LASTPIN (2525 900) $PN BU80
J 2
(2515 910);
DISPLAY 0.680851 (2515 910);
PAINT MONO (2515 910);
FORCEPROP 0 LASTPIN (2525 950) $PN BU82
J 2
(2515 960);
DISPLAY 0.680851 (2515 960);
PAINT MONO (2515 960);
FORCEPROP 0 LASTPIN (2525 1000) $PN BU84
J 2
(2515 1010);
DISPLAY 0.680851 (2515 1010);
PAINT MONO (2515 1010);
FORCEPROP 0 LASTPIN (2525 1050) $PN BU86
J 2
(2515 1060);
DISPLAY 0.680851 (2515 1060);
PAINT MONO (2515 1060);
FORCEPROP 0 LASTPIN (2525 1100) $PN BU88
J 2
(2515 1110);
DISPLAY 0.680851 (2515 1110);
PAINT MONO (2515 1110);
FORCEPROP 0 LASTPIN (2525 1150) $PN BU90
J 2
(2515 1160);
DISPLAY 0.680851 (2515 1160);
PAINT MONO (2515 1160);
FORCEPROP 0 LASTPIN (2525 1200) $PN BV32
J 2
(2515 1210);
DISPLAY 0.680851 (2515 1210);
PAINT MONO (2515 1210);
FORCEPROP 0 LASTPIN (2525 1250) $PN BV34
J 2
(2515 1260);
DISPLAY 0.680851 (2515 1260);
PAINT MONO (2515 1260);
FORCEPROP 0 LASTPIN (2525 1300) $PN BV36
J 2
(2515 1310);
DISPLAY 0.680851 (2515 1310);
PAINT MONO (2515 1310);
FORCEPROP 0 LASTPIN (2525 1350) $PN BV38
J 2
(2515 1360);
DISPLAY 0.680851 (2515 1360);
PAINT MONO (2515 1360);
FORCEPROP 0 LASTPIN (2525 1400) $PN BV40
J 2
(2515 1410);
DISPLAY 0.680851 (2515 1410);
PAINT MONO (2515 1410);
FORCEPROP 0 LASTPIN (2525 1450) $PN BV42
J 2
(2515 1460);
DISPLAY 0.680851 (2515 1460);
PAINT MONO (2515 1460);
FORCEPROP 0 LASTPIN (2525 1500) $PN BV44
J 2
(2515 1510);
DISPLAY 0.680851 (2515 1510);
PAINT MONO (2515 1510);
FORCEPROP 0 LASTPIN (2525 1550) $PN BV47
J 2
(2515 1560);
DISPLAY 0.680851 (2515 1560);
PAINT MONO (2515 1560);
FORCEPROP 0 LASTPIN (2525 1600) $PN BV49
J 2
(2515 1610);
DISPLAY 0.680851 (2515 1610);
PAINT MONO (2515 1610);
FORCEPROP 0 LASTPIN (2525 1650) $PN BV51
J 2
(2515 1660);
DISPLAY 0.680851 (2515 1660);
PAINT MONO (2515 1660);
FORCEPROP 0 LASTPIN (2525 1700) $PN BV53
J 2
(2515 1710);
DISPLAY 0.680851 (2515 1710);
PAINT MONO (2515 1710);
FORCEPROP 0 LASTPIN (2525 1750) $PN BV55
J 2
(2515 1760);
DISPLAY 0.680851 (2515 1760);
PAINT MONO (2515 1760);
FORCEPROP 0 LASTPIN (2525 1800) $PN BV57
J 2
(2515 1810);
DISPLAY 0.680851 (2515 1810);
PAINT MONO (2515 1810);
FORCEPROP 0 LASTPIN (2525 1850) $PN BV59
J 2
(2515 1860);
DISPLAY 0.680851 (2515 1860);
PAINT MONO (2515 1860);
FORCEPROP 0 LASTPIN (2525 1900) $PN BV61
J 2
(2515 1910);
DISPLAY 0.680851 (2515 1910);
PAINT MONO (2515 1910);
FORCEPROP 0 LASTPIN (2525 1950) $PN BV63
J 2
(2515 1960);
DISPLAY 0.680851 (2515 1960);
PAINT MONO (2515 1960);
FORCEPROP 0 LASTPIN (2525 2000) $PN BV65
J 2
(2515 2010);
DISPLAY 0.680851 (2515 2010);
PAINT MONO (2515 2010);
FORCEPROP 0 LASTPIN (2525 2050) $PN BV67
J 2
(2515 2060);
DISPLAY 0.680851 (2515 2060);
PAINT MONO (2515 2060);
FORCEPROP 0 LASTPIN (2525 2100) $PN BV69
J 2
(2515 2110);
DISPLAY 0.680851 (2515 2110);
PAINT MONO (2515 2110);
FORCEPROP 0 LASTPIN (2525 2150) $PN BV71
J 2
(2515 2160);
DISPLAY 0.680851 (2515 2160);
PAINT MONO (2515 2160);
FORCEPROP 0 LASTPIN (2525 2200) $PN BV73
J 2
(2515 2210);
DISPLAY 0.680851 (2515 2210);
PAINT MONO (2515 2210);
FORCEPROP 0 LASTPIN (2525 2250) $PN BV75
J 2
(2515 2260);
DISPLAY 0.680851 (2515 2260);
PAINT MONO (2515 2260);
FORCEPROP 0 LASTPIN (2525 2300) $PN BV77
J 2
(2515 2310);
DISPLAY 0.680851 (2515 2310);
PAINT MONO (2515 2310);
FORCEPROP 0 LASTPIN (2525 2350) $PN BV79
J 2
(2515 2360);
DISPLAY 0.680851 (2515 2360);
PAINT MONO (2515 2360);
FORCEPROP 0 LASTPIN (2525 2400) $PN BV81
J 2
(2515 2410);
DISPLAY 0.680851 (2515 2410);
PAINT MONO (2515 2410);
FORCEPROP 0 LASTPIN (2525 2450) $PN BV83
J 2
(2515 2460);
DISPLAY 0.680851 (2515 2460);
PAINT MONO (2515 2460);
FORCEPROP 0 LASTPIN (2525 2500) $PN BV85
J 2
(2515 2510);
DISPLAY 0.680851 (2515 2510);
PAINT MONO (2515 2510);
FORCEPROP 0 LASTPIN (2525 2550) $PN BV87
J 2
(2515 2560);
DISPLAY 0.680851 (2515 2560);
PAINT MONO (2515 2560);
FORCEPROP 0 LASTPIN (2525 2600) $PN BV89
J 2
(2515 2610);
DISPLAY 0.680851 (2515 2610);
PAINT MONO (2515 2610);
FORCEPROP 0 LASTPIN (2525 2650) $PN BW33
J 2
(2515 2660);
DISPLAY 0.680851 (2515 2660);
PAINT MONO (2515 2660);
FORCEPROP 0 LASTPIN (2525 2700) $PN BW35
J 2
(2515 2710);
DISPLAY 0.680851 (2515 2710);
PAINT MONO (2515 2710);
FORCEPROP 0 LASTPIN (2525 2750) $PN BW37
J 2
(2515 2760);
DISPLAY 0.680851 (2515 2760);
PAINT MONO (2515 2760);
FORCEPROP 0 LASTPIN (2525 2800) $PN BW39
J 2
(2515 2810);
DISPLAY 0.680851 (2515 2810);
PAINT MONO (2515 2810);
FORCEPROP 0 LASTPIN (2525 2850) $PN BW41
J 2
(2515 2860);
DISPLAY 0.680851 (2515 2860);
PAINT MONO (2515 2860);
FORCEPROP 0 LASTPIN (2525 2900) $PN BW43
J 2
(2515 2910);
DISPLAY 0.680851 (2515 2910);
PAINT MONO (2515 2910);
FORCEPROP 0 LASTPIN (2525 2950) $PN BW45
J 2
(2515 2960);
DISPLAY 0.680851 (2515 2960);
PAINT MONO (2515 2960);
FORCEPROP 0 LASTPIN (2525 3000) $PN BW48
J 2
(2515 3010);
DISPLAY 0.680851 (2515 3010);
PAINT MONO (2515 3010);
FORCEPROP 0 LASTPIN (2525 3050) $PN BW50
J 2
(2515 3060);
DISPLAY 0.680851 (2515 3060);
PAINT MONO (2515 3060);
FORCEPROP 0 LASTPIN (2525 3100) $PN BW52
J 2
(2515 3110);
DISPLAY 0.680851 (2515 3110);
PAINT MONO (2515 3110);
FORCEPROP 0 LASTPIN (2525 3150) $PN BW54
J 2
(2515 3160);
DISPLAY 0.680851 (2515 3160);
PAINT MONO (2515 3160);
FORCEPROP 0 LASTPIN (2525 3200) $PN BW56
J 2
(2515 3210);
DISPLAY 0.680851 (2515 3210);
PAINT MONO (2515 3210);
FORCEPROP 0 LASTPIN (2525 3250) $PN BW58
J 2
(2515 3260);
DISPLAY 0.680851 (2515 3260);
PAINT MONO (2515 3260);
FORCEPROP 0 LASTPIN (2525 3300) $PN BW60
J 2
(2515 3310);
DISPLAY 0.680851 (2515 3310);
PAINT MONO (2515 3310);
FORCEPROP 0 LASTPIN (2525 3350) $PN BW62
J 2
(2515 3360);
DISPLAY 0.680851 (2515 3360);
PAINT MONO (2515 3360);
FORCEPROP 0 LASTPIN (2525 3400) $PN BW64
J 2
(2515 3410);
DISPLAY 0.680851 (2515 3410);
PAINT MONO (2515 3410);
FORCEPROP 0 LASTPIN (2525 3450) $PN BW66
J 2
(2515 3460);
DISPLAY 0.680851 (2515 3460);
PAINT MONO (2515 3460);
FORCEPROP 0 LASTPIN (2525 3500) $PN BW68
J 2
(2515 3510);
DISPLAY 0.680851 (2515 3510);
PAINT MONO (2515 3510);
FORCEPROP 0 LASTPIN (2525 3550) $PN BW70
J 2
(2515 3560);
DISPLAY 0.680851 (2515 3560);
PAINT MONO (2515 3560);
FORCEPROP 0 LASTPIN (2525 3600) $PN BW72
J 2
(2515 3610);
DISPLAY 0.680851 (2515 3610);
PAINT MONO (2515 3610);
FORCEPROP 0 LASTPIN (2525 3650) $PN BW74
J 2
(2515 3660);
DISPLAY 0.680851 (2515 3660);
PAINT MONO (2515 3660);
FORCEPROP 0 LASTPIN (2525 3700) $PN BW76
J 2
(2515 3710);
DISPLAY 0.680851 (2515 3710);
PAINT MONO (2515 3710);
FORCEPROP 0 LASTPIN (2525 3750) $PN BW78
J 2
(2515 3760);
DISPLAY 0.680851 (2515 3760);
PAINT MONO (2515 3760);
FORCEPROP 1 LAST CDS_LMAN_SYM_OUTLINE -1050,2000,1050,-2000
J 0
(3725 1900);
DISPLAY 0.468085 (3725 1900);
PAINT GREEN (3725 1900);
DISPLAY INVISIBLE (3725 1900);
FORCEPROP 1 LAST NEEDS_NO_SIZE TRUE
J 0
(3725 1900);
DISPLAY 0.723404 (3725 1900);
PAINT GREEN (3725 1900);
DISPLAY INVISIBLE (3725 1900);
FORCEPROP 2 LAST CDS_LIB pure_quanta
J 0
(3725 1900);
DISPLAY INVISIBLE (3725 1900);
FORCEPROP 2 LAST CDS_LOCATION U1
J 0
(2675 4225);
DISPLAY 1.021277 (2675 4225);
DISPLAY INVISIBLE (2675 4225);
FORCEPROP 0 LAST $SEC 27
J 0
(2675 4225);
DISPLAY 0.680851 (2675 4225);
PAINT MONO (2675 4225);
DISPLAY INVISIBLE (2675 4225);
FORCEPROP 2 LAST CDS_SEC 27
J 0
(2675 4225);
DISPLAY 1.021277 (2675 4225);
DISPLAY INVISIBLE (2675 4225);
FORCEPROP 1 LAST PATH I3
J 0
(3725 1900);
DISPLAY 0.723404 (3725 1900);
PAINT GREEN (3725 1900);
DISPLAY INVISIBLE (3725 1900);
FORCEADD VCC_CORE..1
(800 3975);
FORCEPROP 3 LASTPIN (800 3925) SIG_NAME PVCCIN_CPU1\g
J 0
(810 3935);
DISPLAY 0.659574 (810 3935);
PAINT MONO (810 3935);
DISPLAY INVISIBLE (810 3935);
FORCEPROP 1 LAST HDL_POWER PVCCIN_CPU1
J 1
(800 4025);
DISPLAY 1.148936 (800 4025);
PAINT GREEN (800 4025);
FORCEPROP 2 LAST CDS_LIB logical_power
J 0
(800 3975);
PAINT MONO (800 3975);
DISPLAY INVISIBLE (800 3975);
FORCEPROP 1 LAST PATH I4
J 0
(850 4000);
DISPLAY 0.872340 (850 4000);
PAINT AQUA (850 4000);
DISPLAY INVISIBLE (850 4000);
FORCEADD VCC_CORE..1
(2275 3975);
FORCEPROP 3 LASTPIN (2275 3925) SIG_NAME PVCCIN_CPU1\g
J 0
(2285 3935);
DISPLAY 0.659574 (2285 3935);
PAINT MONO (2285 3935);
DISPLAY INVISIBLE (2285 3935);
FORCEPROP 1 LAST HDL_POWER PVCCIN_CPU1
J 1
(2275 4025);
DISPLAY 1.148936 (2275 4025);
PAINT GREEN (2275 4025);
FORCEPROP 2 LAST CDS_LIB logical_power
J 0
(2275 3975);
PAINT MONO (2275 3975);
DISPLAY INVISIBLE (2275 3975);
FORCEPROP 1 LAST PATH I5
J 0
(2325 4000);
DISPLAY 0.872340 (2325 4000);
PAINT AQUA (2325 4000);
DISPLAY INVISIBLE (2325 4000);
FORCEADD VCC_CORE..1
(5175 3975);
FORCEPROP 3 LASTPIN (5175 3925) SIG_NAME PVCCIN_CPU1\g
J 0
(5185 3935);
DISPLAY 0.659574 (5185 3935);
PAINT MONO (5185 3935);
DISPLAY INVISIBLE (5185 3935);
FORCEPROP 1 LAST HDL_POWER PVCCIN_CPU1
J 1
(5175 4025);
DISPLAY 1.148936 (5175 4025);
PAINT GREEN (5175 4025);
FORCEPROP 2 LAST CDS_LIB logical_power
J 0
(5175 3975);
PAINT MONO (5175 3975);
DISPLAY INVISIBLE (5175 3975);
FORCEPROP 1 LAST PATH I6
J 0
(5225 4000);
DISPLAY 0.872340 (5225 4000);
PAINT AQUA (5225 4000);
DISPLAY INVISIBLE (5225 4000);
FORCEADD QUANTA_TITLE_BLOCK_C..1
(6100 -1400);
FORCEPROP 0 LAST CDS_CON_LAST_MODIFIED Fri Aug 25 14:00:48 2023
J 0
(4215 -1385);
PAINT MONO (4215 -1385);
DISPLAY INVISIBLE (4215 -1385);
FORCEPROP 2 LAST CUSTOM_TXT_CDS <XR_PAGE_TITLE>
J 0
(-1790 3850);
DISPLAY 0.638298 (-1790 3850);
PAINT PINK (-1790 3850);
DISPLAY INVISIBLE (-1790 3850);
FORCEPROP 2 LAST CUSTOM_TXT_CDS <CON_PAGE_NUM> OF <CON_TOTAL_PAGES>
J 0
(5654 -1382);
DISPLAY 0.978723 (5654 -1382);
FORCEPROP 2 LAST CUSTOM_TXT_CDS <Q_NUMBER>
J 0
(4697 -1297);
DISPLAY 1.212766 (4697 -1297);
FORCEPROP 2 LAST CUSTOM_TXT_CDS <CON_LAST_MODIFIED>
J 0
(4215 -1385);
DISPLAY 0.978723 (4215 -1385);
FORCEPROP 2 LAST CUSTOM_TXT_CDS <Q_PROJ>
J 0
(3718 -1298);
DISPLAY 1.212766 (3718 -1298);
FORCEPROP 2 LAST CUSTOM_TXT_CDS <Q_REV>
J 0
(5916 -1297);
DISPLAY 1.212766 (5916 -1297);
FORCEPROP 1 LAST CUSTOM_TXT_CDS <NAME_2>
J 0
(2925 -1350);
FORCEPROP 1 LAST CUSTOM_TXT_CDS <NAME_1>
J 0
(2925 -1225);
FORCEPROP 1 LAST Q_TITLE SPR CPU1 POWER - VCCIN (24 OF 30)
J 0
(-3266 -1374);
DISPLAY 1.957447 (-3266 -1374);
PAINT GREEN (-3266 -1374);
FORCEPROP 1 LAST Q_DEPT 
J 1
(2337 -1351);
DISPLAY 1.957447 (2337 -1351);
PAINT GREEN (2337 -1351);
FORCEPROP 1 LAST COMMENT_BODY TRUE
J 0
(6112 -1413);
DISPLAY 0.978723 (6112 -1413);
PAINT GREEN (6112 -1413);
DISPLAY INVISIBLE (6112 -1413);
FORCEPROP 2 LAST CDS_XR_PAGE_TITLE CR-67 : @S9S_MB_2U_LIB.S9S_MB_2U(SCH_1):PAGE67
J 0
(-1790 3850);
DISPLAY 0.638298 (-1790 3850);
PAINT PINK (-1790 3850);
DISPLAY INVISIBLE (-1790 3850);
FORCEPROP 2 LAST CDS_LIB pure_quanta
J 0
(6100 -1400);
PAINT MONO (6100 -1400);
DISPLAY INVISIBLE (6100 -1400);
FORCEPROP 1 LAST CDS_LMAN_SYM_OUTLINE -9475,6775,100,-125
J 0
(6100 -1400);
DISPLAY 0.468085 (6100 -1400);
PAINT GREEN (6100 -1400);
DISPLAY INVISIBLE (6100 -1400);
FORCEPROP 2 LAST PAGE_BORDER TRUE
J 0
(-1790 3850);
DISPLAY 0.638298 (-1790 3850);
PAINT PINK (-1790 3850);
DISPLAY INVISIBLE (-1790 3850);
WIRE 16 -1 (2275 3925)(2275 3750);
WIRE 16 -1 (5175 3925)(5175 3750);
WIRE 16 -1 (800 3925)(800 3750);
WIRE 16 -1 (-2100 3925)(-2100 3750);
WIRE 16 -1 (2525 3750)(2275 3750);
WIRE 16 -1 (2275 3750)(2275 3700);
WIRE 16 -1 (2525 3700)(2275 3700);
WIRE 16 -1 (2275 3700)(2275 3650);
WIRE 16 -1 (2525 3650)(2275 3650);
WIRE 16 -1 (2275 3650)(2275 3600);
WIRE 16 -1 (2525 3600)(2275 3600);
WIRE 16 -1 (2525 3550)(2275 3550);
WIRE 16 -1 (2275 3600)(2275 3550);
WIRE 16 -1 (2275 3550)(2275 3500);
WIRE 16 -1 (2525 3500)(2275 3500);
WIRE 16 -1 (2275 3500)(2275 3450);
WIRE 16 -1 (2525 3450)(2275 3450);
WIRE 16 -1 (2275 3450)(2275 3400);
WIRE 16 -1 (2525 3400)(2275 3400);
WIRE 16 -1 (2275 3400)(2275 3350);
WIRE 16 -1 (2525 3350)(2275 3350);
WIRE 16 -1 (2275 3350)(2275 3300);
WIRE 16 -1 (2525 3300)(2275 3300);
WIRE 16 -1 (2275 3300)(2275 3250);
WIRE 16 -1 (2525 3250)(2275 3250);
WIRE 16 -1 (2275 3250)(2275 3200);
WIRE 16 -1 (2525 3200)(2275 3200);
WIRE 16 -1 (2275 3200)(2275 3150);
WIRE 16 -1 (2525 3150)(2275 3150);
WIRE 16 -1 (2275 3150)(2275 3100);
WIRE 16 -1 (2525 3100)(2275 3100);
WIRE 16 -1 (2275 3050)(2525 3050);
WIRE 16 -1 (2275 3100)(2275 3050);
WIRE 16 -1 (2275 3050)(2275 3000);
WIRE 16 -1 (2275 3000)(2525 3000);
WIRE 16 -1 (2275 3000)(2275 2950);
WIRE 16 -1 (2275 2950)(2525 2950);
WIRE 16 -1 (2275 2950)(2275 2900);
WIRE 16 -1 (2275 2900)(2525 2900);
WIRE 16 -1 (2275 2900)(2275 2850);
WIRE 16 -1 (2275 2850)(2525 2850);
WIRE 16 -1 (2275 2850)(2275 2800);
WIRE 16 -1 (2275 2800)(2525 2800);
WIRE 16 -1 (2275 2800)(2275 2750);
WIRE 16 -1 (2275 2750)(2525 2750);
WIRE 16 -1 (2275 2750)(2275 2700);
WIRE 16 -1 (2275 2700)(2525 2700);
WIRE 16 -1 (2275 2700)(2275 2650);
WIRE 16 -1 (2275 2650)(2525 2650);
WIRE 16 -1 (2275 2650)(2275 2600);
WIRE 16 -1 (2275 2600)(2525 2600);
WIRE 16 -1 (2275 2550)(2525 2550);
WIRE 16 -1 (2275 2600)(2275 2550);
WIRE 16 -1 (2275 2550)(2275 2500);
WIRE 16 -1 (2275 2500)(2525 2500);
WIRE 16 -1 (2275 2500)(2275 2450);
WIRE 16 -1 (2275 2450)(2525 2450);
WIRE 16 -1 (2275 2450)(2275 2400);
WIRE 16 -1 (2275 2400)(2525 2400);
WIRE 16 -1 (2275 2400)(2275 2350);
WIRE 16 -1 (2275 2350)(2525 2350);
WIRE 16 -1 (2275 2350)(2275 2300);
WIRE 16 -1 (2275 2300)(2525 2300);
WIRE 16 -1 (2275 2300)(2275 2250);
WIRE 16 -1 (2275 2250)(2525 2250);
WIRE 16 -1 (2275 2250)(2275 2200);
WIRE 16 -1 (2275 2200)(2525 2200);
WIRE 16 -1 (2275 2200)(2275 2150);
WIRE 16 -1 (2275 2150)(2525 2150);
WIRE 16 -1 (2275 2150)(2275 2100);
WIRE 16 -1 (2275 2100)(2525 2100);
WIRE 16 -1 (2275 2100)(2275 2050);
WIRE 16 -1 (2275 2050)(2525 2050);
WIRE 16 -1 (2275 2000)(2525 2000);
WIRE 16 -1 (2275 2050)(2275 2000);
WIRE 16 -1 (2275 2000)(2275 1950);
WIRE 16 -1 (2275 1950)(2525 1950);
WIRE 16 -1 (2275 1950)(2275 1900);
WIRE 16 -1 (2275 1900)(2525 1900);
WIRE 16 -1 (2275 1900)(2275 1850);
WIRE 16 -1 (2275 1850)(2525 1850);
WIRE 16 -1 (2275 1850)(2275 1800);
WIRE 16 -1 (2275 1800)(2525 1800);
WIRE 16 -1 (2275 1800)(2275 1750);
WIRE 16 -1 (2275 1750)(2525 1750);
WIRE 16 -1 (2275 1750)(2275 1700);
WIRE 16 -1 (2275 1700)(2525 1700);
WIRE 16 -1 (2275 1700)(2275 1650);
WIRE 16 -1 (2275 1650)(2525 1650);
WIRE 16 -1 (2275 1650)(2275 1600);
WIRE 16 -1 (2275 1600)(2525 1600);
WIRE 16 -1 (2275 1600)(2275 1550);
WIRE 16 -1 (2275 1550)(2525 1550);
WIRE 16 -1 (2275 1500)(2525 1500);
WIRE 16 -1 (2275 1550)(2275 1500);
WIRE 16 -1 (2275 1500)(2275 1450);
WIRE 16 -1 (2275 1450)(2525 1450);
WIRE 16 -1 (2275 1450)(2275 1400);
WIRE 16 -1 (2275 1400)(2525 1400);
WIRE 16 -1 (2275 1400)(2275 1350);
WIRE 16 -1 (2275 1350)(2525 1350);
WIRE 16 -1 (2275 1350)(2275 1300);
WIRE 16 -1 (2275 1300)(2525 1300);
WIRE 16 -1 (2275 1300)(2275 1250);
WIRE 16 -1 (2275 1250)(2525 1250);
WIRE 16 -1 (2275 1250)(2275 1200);
WIRE 16 -1 (2275 1200)(2525 1200);
WIRE 16 -1 (2275 1200)(2275 1150);
WIRE 16 -1 (2275 1150)(2525 1150);
WIRE 16 -1 (2275 1150)(2275 1100);
WIRE 16 -1 (2275 1100)(2525 1100);
WIRE 16 -1 (2275 1100)(2275 1050);
WIRE 16 -1 (2275 1050)(2525 1050);
WIRE 16 -1 (2275 1000)(2525 1000);
WIRE 16 -1 (2275 1050)(2275 1000);
WIRE 16 -1 (2275 1000)(2275 950);
WIRE 16 -1 (2525 950)(2275 950);
WIRE 16 -1 (2275 950)(2275 900);
WIRE 16 -1 (2525 900)(2275 900);
WIRE 16 -1 (2275 900)(2275 850);
WIRE 16 -1 (2525 850)(2275 850);
WIRE 16 -1 (2275 850)(2275 800);
WIRE 16 -1 (2525 800)(2275 800);
WIRE 16 -1 (2275 800)(2275 750);
WIRE 16 -1 (2525 750)(2275 750);
WIRE 16 -1 (2275 750)(2275 700);
WIRE 16 -1 (2525 700)(2275 700);
WIRE 16 -1 (2275 700)(2275 650);
WIRE 16 -1 (2525 650)(2275 650);
WIRE 16 -1 (2275 650)(2275 600);
WIRE 16 -1 (2525 600)(2275 600);
WIRE 16 -1 (2275 600)(2275 550);
WIRE 16 -1 (2525 550)(2275 550);
WIRE 16 -1 (2525 500)(2275 500);
WIRE 16 -1 (2275 550)(2275 500);
WIRE 16 -1 (2275 500)(2275 450);
WIRE 16 -1 (2525 450)(2275 450);
WIRE 16 -1 (2275 450)(2275 400);
WIRE 16 -1 (2525 400)(2275 400);
WIRE 16 -1 (2275 350)(2275 400);
WIRE 16 -1 (2525 350)(2275 350);
WIRE 16 -1 (2275 350)(2275 300);
WIRE 16 -1 (2525 300)(2275 300);
WIRE 16 -1 (2275 250)(2275 300);
WIRE 16 -1 (2525 250)(2275 250);
WIRE 16 -1 (2275 250)(2275 200);
WIRE 16 -1 (2525 200)(2275 200);
WIRE 16 -1 (2275 150)(2275 200);
WIRE 16 -1 (2525 150)(2275 150);
WIRE 16 -1 (2275 150)(2275 100);
WIRE 16 -1 (2525 100)(2275 100);
WIRE 16 -1 (2275 50)(2275 100);
WIRE 16 -1 (2525 50)(2275 50);
WIRE 16 -1 (5175 3750)(4925 3750);
WIRE 16 -1 (5175 3700)(4925 3700);
WIRE 16 -1 (5175 3750)(5175 3700);
WIRE 16 -1 (5175 3650)(4925 3650);
WIRE 16 -1 (5175 3700)(5175 3650);
WIRE 16 -1 (5175 3600)(4925 3600);
WIRE 16 -1 (5175 3650)(5175 3600);
WIRE 16 -1 (5175 3550)(4925 3550);
WIRE 16 -1 (5175 3600)(5175 3550);
WIRE 16 -1 (5175 3500)(4925 3500);
WIRE 16 -1 (5175 3550)(5175 3500);
WIRE 16 -1 (5175 3450)(4925 3450);
WIRE 16 -1 (5175 3500)(5175 3450);
WIRE 16 -1 (5175 3400)(4925 3400);
WIRE 16 -1 (5175 3450)(5175 3400);
WIRE 16 -1 (5175 3350)(4925 3350);
WIRE 16 -1 (5175 3400)(5175 3350);
WIRE 16 -1 (5175 3300)(4925 3300);
WIRE 16 -1 (5175 3350)(5175 3300);
WIRE 16 -1 (5175 3250)(4925 3250);
WIRE 16 -1 (5175 3300)(5175 3250);
WIRE 16 -1 (5175 3200)(4925 3200);
WIRE 16 -1 (5175 3250)(5175 3200);
WIRE 16 -1 (5175 3150)(4925 3150);
WIRE 16 -1 (5175 3200)(5175 3150);
WIRE 16 -1 (5175 3100)(4925 3100);
WIRE 16 -1 (5175 3150)(5175 3100);
WIRE 16 -1 (4925 3050)(5175 3050);
WIRE 16 -1 (5175 3100)(5175 3050);
WIRE 16 -1 (4925 3000)(5175 3000);
WIRE 16 -1 (5175 3050)(5175 3000);
WIRE 16 -1 (4925 2950)(5175 2950);
WIRE 16 -1 (5175 3000)(5175 2950);
WIRE 16 -1 (4925 2900)(5175 2900);
WIRE 16 -1 (5175 2950)(5175 2900);
WIRE 16 -1 (4925 2850)(5175 2850);
WIRE 16 -1 (5175 2900)(5175 2850);
WIRE 16 -1 (4925 2800)(5175 2800);
WIRE 16 -1 (5175 2850)(5175 2800);
WIRE 16 -1 (4925 2750)(5175 2750);
WIRE 16 -1 (5175 2800)(5175 2750);
WIRE 16 -1 (4925 2700)(5175 2700);
WIRE 16 -1 (5175 2750)(5175 2700);
WIRE 16 -1 (4925 2650)(5175 2650);
WIRE 16 -1 (5175 2700)(5175 2650);
WIRE 16 -1 (4925 2600)(5175 2600);
WIRE 16 -1 (5175 2650)(5175 2600);
WIRE 16 -1 (4925 2550)(5175 2550);
WIRE 16 -1 (5175 2600)(5175 2550);
WIRE 16 -1 (4925 2500)(5175 2500);
WIRE 16 -1 (5175 2550)(5175 2500);
WIRE 16 -1 (4925 2450)(5175 2450);
WIRE 16 -1 (5175 2500)(5175 2450);
WIRE 16 -1 (4925 2400)(5175 2400);
WIRE 16 -1 (5175 2450)(5175 2400);
WIRE 16 -1 (4925 2350)(5175 2350);
WIRE 16 -1 (5175 2400)(5175 2350);
WIRE 16 -1 (4925 2300)(5175 2300);
WIRE 16 -1 (5175 2350)(5175 2300);
WIRE 16 -1 (4925 2250)(5175 2250);
WIRE 16 -1 (5175 2300)(5175 2250);
WIRE 16 -1 (4925 2200)(5175 2200);
WIRE 16 -1 (5175 2250)(5175 2200);
WIRE 16 -1 (4925 2150)(5175 2150);
WIRE 16 -1 (5175 2200)(5175 2150);
WIRE 16 -1 (4925 2100)(5175 2100);
WIRE 16 -1 (5175 2150)(5175 2100);
WIRE 16 -1 (5175 2050)(4925 2050);
WIRE 16 -1 (5175 2100)(5175 2050);
WIRE 16 -1 (4925 2000)(5175 2000);
WIRE 16 -1 (5175 2050)(5175 2000);
WIRE 16 -1 (4925 1950)(5175 1950);
WIRE 16 -1 (5175 2000)(5175 1950);
WIRE 16 -1 (4925 1900)(5175 1900);
WIRE 16 -1 (5175 1950)(5175 1900);
WIRE 16 -1 (4925 1850)(5175 1850);
WIRE 16 -1 (5175 1900)(5175 1850);
WIRE 16 -1 (4925 1800)(5175 1800);
WIRE 16 -1 (5175 1850)(5175 1800);
WIRE 16 -1 (4925 1750)(5175 1750);
WIRE 16 -1 (5175 1800)(5175 1750);
WIRE 16 -1 (4925 1700)(5175 1700);
WIRE 16 -1 (5175 1750)(5175 1700);
WIRE 16 -1 (4925 1650)(5175 1650);
WIRE 16 -1 (5175 1700)(5175 1650);
WIRE 16 -1 (4925 1600)(5175 1600);
WIRE 16 -1 (5175 1650)(5175 1600);
WIRE 16 -1 (4925 1550)(5175 1550);
WIRE 16 -1 (5175 1600)(5175 1550);
WIRE 16 -1 (4925 1500)(5175 1500);
WIRE 16 -1 (5175 1550)(5175 1500);
WIRE 16 -1 (4925 1450)(5175 1450);
WIRE 16 -1 (5175 1500)(5175 1450);
WIRE 16 -1 (4925 1400)(5175 1400);
WIRE 16 -1 (5175 1450)(5175 1400);
WIRE 16 -1 (4925 1350)(5175 1350);
WIRE 16 -1 (5175 1400)(5175 1350);
WIRE 16 -1 (4925 1300)(5175 1300);
WIRE 16 -1 (5175 1350)(5175 1300);
WIRE 16 -1 (4925 1250)(5175 1250);
WIRE 16 -1 (5175 1300)(5175 1250);
WIRE 16 -1 (4925 1200)(5175 1200);
WIRE 16 -1 (5175 1250)(5175 1200);
WIRE 16 -1 (4925 1150)(5175 1150);
WIRE 16 -1 (5175 1200)(5175 1150);
WIRE 16 -1 (4925 1100)(5175 1100);
WIRE 16 -1 (5175 1150)(5175 1100);
WIRE 16 -1 (4925 1050)(5175 1050);
WIRE 16 -1 (5175 1100)(5175 1050);
WIRE 16 -1 (5175 1000)(4925 1000);
WIRE 16 -1 (5175 1050)(5175 1000);
WIRE 16 -1 (5175 950)(4925 950);
WIRE 16 -1 (5175 1000)(5175 950);
WIRE 16 -1 (5175 900)(4925 900);
WIRE 16 -1 (5175 950)(5175 900);
WIRE 16 -1 (5175 850)(4925 850);
WIRE 16 -1 (5175 900)(5175 850);
WIRE 16 -1 (5175 800)(4925 800);
WIRE 16 -1 (5175 850)(5175 800);
WIRE 16 -1 (5175 750)(4925 750);
WIRE 16 -1 (5175 800)(5175 750);
WIRE 16 -1 (5175 700)(4925 700);
WIRE 16 -1 (5175 750)(5175 700);
WIRE 16 -1 (5175 650)(4925 650);
WIRE 16 -1 (5175 700)(5175 650);
WIRE 16 -1 (5175 600)(4925 600);
WIRE 16 -1 (5175 650)(5175 600);
WIRE 16 -1 (5175 550)(4925 550);
WIRE 16 -1 (5175 600)(5175 550);
WIRE 16 -1 (5175 500)(4925 500);
WIRE 16 -1 (5175 550)(5175 500);
WIRE 16 -1 (5175 450)(4925 450);
WIRE 16 -1 (5175 500)(5175 450);
WIRE 16 -1 (5175 400)(4925 400);
WIRE 16 -1 (5175 450)(5175 400);
WIRE 16 -1 (4925 350)(5175 350);
WIRE 16 -1 (5175 350)(5175 400);
WIRE 16 -1 (5175 300)(4925 300);
WIRE 16 -1 (5175 350)(5175 300);
WIRE 16 -1 (5175 250)(4925 250);
WIRE 16 -1 (5175 300)(5175 250);
WIRE 16 -1 (5175 200)(4925 200);
WIRE 16 -1 (5175 250)(5175 200);
WIRE 16 -1 (5175 150)(4925 150);
WIRE 16 -1 (5175 200)(5175 150);
WIRE 16 -1 (4925 100)(5175 100);
WIRE 16 -1 (5175 100)(5175 150);
WIRE 16 -1 (5175 50)(5175 100);
WIRE 16 -1 (4925 50)(5175 50);
WIRE 16 -1 (-1850 3750)(-2100 3750);
WIRE 16 -1 (-2100 3750)(-2100 3700);
WIRE 16 -1 (-1850 3700)(-2100 3700);
WIRE 16 -1 (-2100 3700)(-2100 3650);
WIRE 16 -1 (-1850 3650)(-2100 3650);
WIRE 16 -1 (-2100 3650)(-2100 3600);
WIRE 16 -1 (-1850 3600)(-2100 3600);
WIRE 16 -1 (-2100 3600)(-2100 3550);
WIRE 16 -1 (-1850 3550)(-2100 3550);
WIRE 16 -1 (-2100 3550)(-2100 3500);
WIRE 16 -1 (-1850 3500)(-2100 3500);
WIRE 16 -1 (-2100 3500)(-2100 3450);
WIRE 16 -1 (-1850 3450)(-2100 3450);
WIRE 16 -1 (-2100 3450)(-2100 3400);
WIRE 16 -1 (-1850 3400)(-2100 3400);
WIRE 16 -1 (-2100 3400)(-2100 3350);
WIRE 16 -1 (-1850 3350)(-2100 3350);
WIRE 16 -1 (-2100 3350)(-2100 3300);
WIRE 16 -1 (-1850 3300)(-2100 3300);
WIRE 16 -1 (-2100 3300)(-2100 3250);
WIRE 16 -1 (-1850 3250)(-2100 3250);
WIRE 16 -1 (-2100 3250)(-2100 3200);
WIRE 16 -1 (-1850 3200)(-2100 3200);
WIRE 16 -1 (-2100 3200)(-2100 3150);
WIRE 16 -1 (-1850 3150)(-2100 3150);
WIRE 16 -1 (-2100 3150)(-2100 3100);
WIRE 16 -1 (-1850 3100)(-2100 3100);
WIRE 16 -1 (-2100 3100)(-2100 3050);
WIRE 16 -1 (-2100 3050)(-1850 3050);
WIRE 16 -1 (-2100 3050)(-2100 3000);
WIRE 16 -1 (-2100 3000)(-1850 3000);
WIRE 16 -1 (-2100 3000)(-2100 2950);
WIRE 16 -1 (-2100 2950)(-1850 2950);
WIRE 16 -1 (-2100 2950)(-2100 2900);
WIRE 16 -1 (-2100 2900)(-1850 2900);
WIRE 16 -1 (-2100 2900)(-2100 2850);
WIRE 16 -1 (-2100 2850)(-1850 2850);
WIRE 16 -1 (-2100 2850)(-2100 2800);
WIRE 16 -1 (-2100 2800)(-1850 2800);
WIRE 16 -1 (-2100 2800)(-2100 2750);
WIRE 16 -1 (-2100 2750)(-1850 2750);
WIRE 16 -1 (-2100 2750)(-2100 2700);
WIRE 16 -1 (-2100 2700)(-1850 2700);
WIRE 16 -1 (-2100 2700)(-2100 2650);
WIRE 16 -1 (-2100 2650)(-1850 2650);
WIRE 16 -1 (-2100 2650)(-2100 2600);
WIRE 16 -1 (-2100 2600)(-1850 2600);
WIRE 16 -1 (-2100 2600)(-2100 2550);
WIRE 16 -1 (-2100 2550)(-1850 2550);
WIRE 16 -1 (-2100 2550)(-2100 2500);
WIRE 16 -1 (-2100 2500)(-1850 2500);
WIRE 16 -1 (-2100 2500)(-2100 2450);
WIRE 16 -1 (-2100 2450)(-1850 2450);
WIRE 16 -1 (-2100 2450)(-2100 2400);
WIRE 16 -1 (-2100 2400)(-1850 2400);
WIRE 16 -1 (-2100 2400)(-2100 2350);
WIRE 16 -1 (-2100 2350)(-1850 2350);
WIRE 16 -1 (-2100 2350)(-2100 2300);
WIRE 16 -1 (-2100 2300)(-1850 2300);
WIRE 16 -1 (-2100 2300)(-2100 2250);
WIRE 16 -1 (-2100 2250)(-1850 2250);
WIRE 16 -1 (-2100 2250)(-2100 2200);
WIRE 16 -1 (-2100 2200)(-1850 2200);
WIRE 16 -1 (-2100 2200)(-2100 2150);
WIRE 16 -1 (-2100 2150)(-1850 2150);
WIRE 16 -1 (-2100 2150)(-2100 2100);
WIRE 16 -1 (-2100 2100)(-1850 2100);
WIRE 16 -1 (-2100 2100)(-2100 2050);
WIRE 16 -1 (-2100 2050)(-1850 2050);
WIRE 16 -1 (-2100 2050)(-2100 2000);
WIRE 16 -1 (-2100 2000)(-1850 2000);
WIRE 16 -1 (-2100 2000)(-2100 1950);
WIRE 16 -1 (-2100 1950)(-1850 1950);
WIRE 16 -1 (-2100 1950)(-2100 1900);
WIRE 16 -1 (-2100 1900)(-1850 1900);
WIRE 16 -1 (-2100 1900)(-2100 1850);
WIRE 16 -1 (-2100 1850)(-1850 1850);
WIRE 16 -1 (-2100 1850)(-2100 1800);
WIRE 16 -1 (-2100 1800)(-1850 1800);
WIRE 16 -1 (-2100 1800)(-2100 1750);
WIRE 16 -1 (-2100 1750)(-1850 1750);
WIRE 16 -1 (-2100 1750)(-2100 1700);
WIRE 16 -1 (-2100 1700)(-1850 1700);
WIRE 16 -1 (-2100 1700)(-2100 1650);
WIRE 16 -1 (-2100 1650)(-1850 1650);
WIRE 16 -1 (-2100 1650)(-2100 1600);
WIRE 16 -1 (-2100 1600)(-1850 1600);
WIRE 16 -1 (-2100 1600)(-2100 1550);
WIRE 16 -1 (-2100 1550)(-1850 1550);
WIRE 16 -1 (-2100 1550)(-2100 1500);
WIRE 16 -1 (-2100 1500)(-1850 1500);
WIRE 16 -1 (-2100 1500)(-2100 1450);
WIRE 16 -1 (-2100 1450)(-1850 1450);
WIRE 16 -1 (-2100 1450)(-2100 1400);
WIRE 16 -1 (-2100 1400)(-1850 1400);
WIRE 16 -1 (-2100 1400)(-2100 1350);
WIRE 16 -1 (-2100 1350)(-1850 1350);
WIRE 16 -1 (-2100 1350)(-2100 1300);
WIRE 16 -1 (-2100 1300)(-1850 1300);
WIRE 16 -1 (-2100 1300)(-2100 1250);
WIRE 16 -1 (-2100 1250)(-1850 1250);
WIRE 16 -1 (-2100 1250)(-2100 1200);
WIRE 16 -1 (-2100 1200)(-1850 1200);
WIRE 16 -1 (-2100 1200)(-2100 1150);
WIRE 16 -1 (-2100 1150)(-1850 1150);
WIRE 16 -1 (-2100 1150)(-2100 1100);
WIRE 16 -1 (-2100 1100)(-1850 1100);
WIRE 16 -1 (-2100 1100)(-2100 1050);
WIRE 16 -1 (-2100 1050)(-1850 1050);
WIRE 16 -1 (-2100 1050)(-2100 1000);
WIRE 16 -1 (-2100 1000)(-1850 1000);
WIRE 16 -1 (-2100 1000)(-2100 950);
WIRE 16 -1 (-1850 950)(-2100 950);
WIRE 16 -1 (-2100 950)(-2100 900);
WIRE 16 -1 (-1850 900)(-2100 900);
WIRE 16 -1 (-2100 900)(-2100 850);
WIRE 16 -1 (-1850 850)(-2100 850);
WIRE 16 -1 (-2100 850)(-2100 800);
WIRE 16 -1 (-1850 800)(-2100 800);
WIRE 16 -1 (-2100 800)(-2100 750);
WIRE 16 -1 (-1850 750)(-2100 750);
WIRE 16 -1 (-2100 750)(-2100 700);
WIRE 16 -1 (-1850 700)(-2100 700);
WIRE 16 -1 (-2100 700)(-2100 650);
WIRE 16 -1 (-1850 650)(-2100 650);
WIRE 16 -1 (-2100 650)(-2100 600);
WIRE 16 -1 (-1850 600)(-2100 600);
WIRE 16 -1 (-2100 600)(-2100 550);
WIRE 16 -1 (-1850 550)(-2100 550);
WIRE 16 -1 (-2100 550)(-2100 500);
WIRE 16 -1 (-1850 500)(-2100 500);
WIRE 16 -1 (-2100 500)(-2100 450);
WIRE 16 -1 (-1850 450)(-2100 450);
WIRE 16 -1 (-2100 450)(-2100 400);
WIRE 16 -1 (-1850 400)(-2100 400);
WIRE 16 -1 (-2100 350)(-2100 400);
WIRE 16 -1 (-1850 350)(-2100 350);
WIRE 16 -1 (-2100 350)(-2100 300);
WIRE 16 -1 (-1850 300)(-2100 300);
WIRE 16 -1 (-2100 250)(-2100 300);
WIRE 16 -1 (-1850 250)(-2100 250);
WIRE 16 -1 (-2100 250)(-2100 200);
WIRE 16 -1 (-1850 200)(-2100 200);
WIRE 16 -1 (-2100 150)(-2100 200);
WIRE 16 -1 (-1850 150)(-2100 150);
WIRE 16 -1 (-2100 150)(-2100 100);
WIRE 16 -1 (-1850 100)(-2100 100);
WIRE 16 -1 (-2100 50)(-2100 100);
WIRE 16 -1 (-1850 50)(-2100 50);
WIRE 16 -1 (800 3750)(550 3750);
WIRE 16 -1 (800 3700)(550 3700);
WIRE 16 -1 (800 3750)(800 3700);
WIRE 16 -1 (800 3650)(550 3650);
WIRE 16 -1 (800 3700)(800 3650);
WIRE 16 -1 (800 3600)(550 3600);
WIRE 16 -1 (800 3650)(800 3600);
WIRE 16 -1 (800 3550)(550 3550);
WIRE 16 -1 (800 3600)(800 3550);
WIRE 16 -1 (800 3500)(550 3500);
WIRE 16 -1 (800 3550)(800 3500);
WIRE 16 -1 (800 3450)(550 3450);
WIRE 16 -1 (800 3500)(800 3450);
WIRE 16 -1 (800 3400)(550 3400);
WIRE 16 -1 (800 3450)(800 3400);
WIRE 16 -1 (800 3350)(550 3350);
WIRE 16 -1 (800 3400)(800 3350);
WIRE 16 -1 (800 3300)(550 3300);
WIRE 16 -1 (800 3350)(800 3300);
WIRE 16 -1 (800 3250)(550 3250);
WIRE 16 -1 (800 3300)(800 3250);
WIRE 16 -1 (800 3200)(550 3200);
WIRE 16 -1 (800 3250)(800 3200);
WIRE 16 -1 (800 3150)(550 3150);
WIRE 16 -1 (800 3200)(800 3150);
WIRE 16 -1 (800 3100)(550 3100);
WIRE 16 -1 (800 3150)(800 3100);
WIRE 16 -1 (550 3050)(800 3050);
WIRE 16 -1 (800 3100)(800 3050);
WIRE 16 -1 (550 3000)(800 3000);
WIRE 16 -1 (800 3050)(800 3000);
WIRE 16 -1 (550 2950)(800 2950);
WIRE 16 -1 (800 3000)(800 2950);
WIRE 16 -1 (550 2900)(800 2900);
WIRE 16 -1 (800 2950)(800 2900);
WIRE 16 -1 (550 2850)(800 2850);
WIRE 16 -1 (800 2900)(800 2850);
WIRE 16 -1 (550 2800)(800 2800);
WIRE 16 -1 (800 2850)(800 2800);
WIRE 16 -1 (550 2750)(800 2750);
WIRE 16 -1 (800 2800)(800 2750);
WIRE 16 -1 (550 2700)(800 2700);
WIRE 16 -1 (800 2750)(800 2700);
WIRE 16 -1 (550 2650)(800 2650);
WIRE 16 -1 (800 2700)(800 2650);
WIRE 16 -1 (550 2600)(800 2600);
WIRE 16 -1 (800 2650)(800 2600);
WIRE 16 -1 (550 2550)(800 2550);
WIRE 16 -1 (800 2600)(800 2550);
WIRE 16 -1 (550 2500)(800 2500);
WIRE 16 -1 (800 2550)(800 2500);
WIRE 16 -1 (550 2450)(800 2450);
WIRE 16 -1 (800 2500)(800 2450);
WIRE 16 -1 (550 2400)(800 2400);
WIRE 16 -1 (800 2450)(800 2400);
WIRE 16 -1 (550 2350)(800 2350);
WIRE 16 -1 (800 2400)(800 2350);
WIRE 16 -1 (550 2300)(800 2300);
WIRE 16 -1 (800 2350)(800 2300);
WIRE 16 -1 (550 2250)(800 2250);
WIRE 16 -1 (800 2300)(800 2250);
WIRE 16 -1 (550 2200)(800 2200);
WIRE 16 -1 (800 2250)(800 2200);
WIRE 16 -1 (550 2150)(800 2150);
WIRE 16 -1 (800 2200)(800 2150);
WIRE 16 -1 (550 2100)(800 2100);
WIRE 16 -1 (800 2150)(800 2100);
WIRE 16 -1 (800 2050)(550 2050);
WIRE 16 -1 (800 2100)(800 2050);
WIRE 16 -1 (550 2000)(800 2000);
WIRE 16 -1 (800 2050)(800 2000);
WIRE 16 -1 (550 1950)(800 1950);
WIRE 16 -1 (800 2000)(800 1950);
WIRE 16 -1 (550 1900)(800 1900);
WIRE 16 -1 (800 1950)(800 1900);
WIRE 16 -1 (550 1850)(800 1850);
WIRE 16 -1 (800 1900)(800 1850);
WIRE 16 -1 (550 1800)(800 1800);
WIRE 16 -1 (800 1850)(800 1800);
WIRE 16 -1 (550 1750)(800 1750);
WIRE 16 -1 (800 1800)(800 1750);
WIRE 16 -1 (550 1700)(800 1700);
WIRE 16 -1 (800 1750)(800 1700);
WIRE 16 -1 (550 1650)(800 1650);
WIRE 16 -1 (800 1700)(800 1650);
WIRE 16 -1 (550 1600)(800 1600);
WIRE 16 -1 (800 1650)(800 1600);
WIRE 16 -1 (550 1550)(800 1550);
WIRE 16 -1 (800 1600)(800 1550);
WIRE 16 -1 (550 1500)(800 1500);
WIRE 16 -1 (800 1550)(800 1500);
WIRE 16 -1 (550 1450)(800 1450);
WIRE 16 -1 (800 1500)(800 1450);
WIRE 16 -1 (550 1400)(800 1400);
WIRE 16 -1 (800 1450)(800 1400);
WIRE 16 -1 (550 1350)(800 1350);
WIRE 16 -1 (800 1400)(800 1350);
WIRE 16 -1 (550 1300)(800 1300);
WIRE 16 -1 (800 1350)(800 1300);
WIRE 16 -1 (550 1250)(800 1250);
WIRE 16 -1 (800 1300)(800 1250);
WIRE 16 -1 (550 1200)(800 1200);
WIRE 16 -1 (800 1250)(800 1200);
WIRE 16 -1 (550 1150)(800 1150);
WIRE 16 -1 (800 1200)(800 1150);
WIRE 16 -1 (550 1100)(800 1100);
WIRE 16 -1 (800 1150)(800 1100);
WIRE 16 -1 (550 1050)(800 1050);
WIRE 16 -1 (800 1100)(800 1050);
WIRE 16 -1 (800 1000)(550 1000);
WIRE 16 -1 (800 1050)(800 1000);
WIRE 16 -1 (800 950)(550 950);
WIRE 16 -1 (800 1000)(800 950);
WIRE 16 -1 (800 900)(550 900);
WIRE 16 -1 (800 950)(800 900);
WIRE 16 -1 (800 850)(550 850);
WIRE 16 -1 (800 900)(800 850);
WIRE 16 -1 (800 800)(550 800);
WIRE 16 -1 (800 850)(800 800);
WIRE 16 -1 (800 750)(550 750);
WIRE 16 -1 (800 800)(800 750);
WIRE 16 -1 (800 700)(550 700);
WIRE 16 -1 (800 750)(800 700);
WIRE 16 -1 (800 650)(550 650);
WIRE 16 -1 (800 700)(800 650);
WIRE 16 -1 (800 600)(550 600);
WIRE 16 -1 (800 650)(800 600);
WIRE 16 -1 (800 550)(550 550);
WIRE 16 -1 (800 600)(800 550);
WIRE 16 -1 (800 500)(550 500);
WIRE 16 -1 (800 550)(800 500);
WIRE 16 -1 (800 450)(550 450);
WIRE 16 -1 (800 500)(800 450);
WIRE 16 -1 (800 400)(550 400);
WIRE 16 -1 (800 450)(800 400);
WIRE 16 -1 (550 350)(800 350);
WIRE 16 -1 (800 350)(800 400);
WIRE 16 -1 (800 300)(550 300);
WIRE 16 -1 (800 350)(800 300);
WIRE 16 -1 (800 250)(550 250);
WIRE 16 -1 (800 300)(800 250);
WIRE 16 -1 (800 200)(550 200);
WIRE 16 -1 (800 250)(800 200);
WIRE 16 -1 (800 150)(550 150);
WIRE 16 -1 (800 200)(800 150);
WIRE 16 -1 (550 100)(800 100);
WIRE 16 -1 (800 100)(800 150);
WIRE 16 -1 (800 50)(800 100);
WIRE 16 -1 (550 50)(800 50);
DOT 1 (800 3000);
DOT 1 (800 3350);
DOT 1 (800 2200);
DOT 1 (-2100 100);
DOT 1 (-2100 150);
DOT 1 (-2100 200);
DOT 1 (-2100 250);
DOT 1 (-2100 300);
DOT 1 (-2100 350);
DOT 1 (-2100 400);
DOT 1 (-2100 450);
DOT 1 (-2100 500);
DOT 1 (-2100 600);
DOT 1 (-2100 550);
DOT 1 (-2100 650);
DOT 1 (-2100 700);
DOT 1 (-2100 750);
DOT 1 (-2100 850);
DOT 1 (-2100 800);
DOT 1 (-2100 900);
DOT 1 (-2100 950);
DOT 1 (-2100 1000);
DOT 1 (-2100 1050);
DOT 1 (-2100 1100);
DOT 1 (-2100 1150);
DOT 1 (-2100 1250);
DOT 1 (-2100 1200);
DOT 1 (-2100 1300);
DOT 1 (-2100 1350);
DOT 1 (-2100 1400);
DOT 1 (-2100 1500);
DOT 1 (-2100 1450);
DOT 1 (-2100 1550);
DOT 1 (-2100 1600);
DOT 1 (-2100 1650);
DOT 1 (-2100 1750);
DOT 1 (-2100 1700);
DOT 1 (-2100 1800);
DOT 1 (-2100 1850);
DOT 1 (-2100 1900);
DOT 1 (-2100 2000);
DOT 1 (-2100 1950);
DOT 1 (-2100 2050);
DOT 1 (-2100 2100);
DOT 1 (-2100 2150);
DOT 1 (-2100 2200);
DOT 1 (-2100 2250);
DOT 1 (-2100 2400);
DOT 1 (-2100 2350);
DOT 1 (-2100 2450);
DOT 1 (-2100 2500);
DOT 1 (-2100 2550);
DOT 1 (-2100 2650);
DOT 1 (-2100 2600);
DOT 1 (-2100 2700);
DOT 1 (-2100 2750);
DOT 1 (-2100 2800);
DOT 1 (-2100 2900);
DOT 1 (-2100 2850);
DOT 1 (-2100 2950);
DOT 1 (-2100 3000);
DOT 1 (-2100 3050);
DOT 1 (-2100 3200);
DOT 1 (-2100 3150);
DOT 1 (-2100 3100);
DOT 1 (-2100 3250);
DOT 1 (-2100 3300);
DOT 1 (-2100 3350);
DOT 1 (-2100 3400);
DOT 1 (-2100 3450);
DOT 1 (-2100 3550);
DOT 1 (-2100 3500);
DOT 1 (-2100 3600);
DOT 1 (-2100 3650);
DOT 1 (-2100 3700);
DOT 1 (-2100 3750);
DOT 1 (800 100);
DOT 1 (800 150);
DOT 1 (800 200);
DOT 1 (800 250);
DOT 1 (800 350);
DOT 1 (800 300);
DOT 1 (800 400);
DOT 1 (800 450);
DOT 1 (800 500);
DOT 1 (800 600);
DOT 1 (800 550);
DOT 1 (800 650);
DOT 1 (800 700);
DOT 1 (800 750);
DOT 1 (800 800);
DOT 1 (800 850);
DOT 1 (800 900);
DOT 1 (800 950);
DOT 1 (800 1000);
DOT 1 (800 1050);
DOT 1 (800 1100);
DOT 1 (800 1150);
DOT 1 (800 1200);
DOT 1 (800 1250);
DOT 1 (800 1300);
DOT 1 (800 1350);
DOT 1 (800 1400);
DOT 1 (800 1450);
DOT 1 (800 1500);
DOT 1 (800 1600);
DOT 1 (800 1550);
DOT 1 (800 1650);
DOT 1 (800 1700);
DOT 1 (800 1750);
DOT 1 (800 1800);
DOT 1 (800 1850);
DOT 1 (800 1900);
DOT 1 (800 2000);
DOT 1 (800 1950);
DOT 1 (800 2050);
DOT 1 (800 2100);
DOT 1 (800 2150);
DOT 1 (800 2250);
DOT 1 (800 2300);
DOT 1 (800 2350);
DOT 1 (800 2400);
DOT 1 (800 2450);
DOT 1 (800 2500);
DOT 1 (800 2550);
DOT 1 (800 2650);
DOT 1 (800 2600);
DOT 1 (800 2700);
DOT 1 (800 2750);
DOT 1 (800 2800);
DOT 1 (800 2850);
DOT 1 (800 2900);
DOT 1 (800 2950);
DOT 1 (800 3050);
DOT 1 (800 3100);
DOT 1 (800 3150);
DOT 1 (800 3200);
DOT 1 (800 3250);
DOT 1 (800 3300);
DOT 1 (800 3400);
DOT 1 (800 3450);
DOT 1 (800 3500);
DOT 1 (800 3550);
DOT 1 (800 3600);
DOT 1 (800 3650);
DOT 1 (800 3700);
DOT 1 (800 3750);
DOT 1 (2275 100);
DOT 1 (2275 150);
DOT 1 (2275 200);
DOT 1 (2275 250);
DOT 1 (2275 350);
DOT 1 (2275 300);
DOT 1 (2275 400);
DOT 1 (2275 450);
DOT 1 (2275 500);
DOT 1 (2275 550);
DOT 1 (2275 600);
DOT 1 (2275 650);
DOT 1 (2275 700);
DOT 1 (2275 750);
DOT 1 (2275 800);
DOT 1 (2275 850);
DOT 1 (2275 900);
DOT 1 (2275 950);
DOT 1 (2275 1000);
DOT 1 (2275 1050);
DOT 1 (2275 1100);
DOT 1 (2275 1150);
DOT 1 (2275 1250);
DOT 1 (2275 1200);
DOT 1 (2275 1300);
DOT 1 (2275 1350);
DOT 1 (2275 1400);
DOT 1 (2275 1450);
DOT 1 (2275 1500);
DOT 1 (2275 1600);
DOT 1 (2275 1550);
DOT 1 (2275 1650);
DOT 1 (2275 1750);
DOT 1 (2275 1700);
DOT 1 (2275 1800);
DOT 1 (2275 1850);
DOT 1 (2275 1900);
DOT 1 (2275 2000);
DOT 1 (2275 1950);
DOT 1 (2275 2050);
DOT 1 (2275 2100);
DOT 1 (2275 2150);
DOT 1 (2275 2200);
DOT 1 (2275 2250);
DOT 1 (2275 2300);
DOT 1 (2275 2350);
DOT 1 (2275 2400);
DOT 1 (2275 2450);
DOT 1 (2275 2500);
DOT 1 (2275 2550);
DOT 1 (2275 2600);
DOT 1 (2275 2650);
DOT 1 (2275 2700);
DOT 1 (2275 2750);
DOT 1 (2275 2800);
DOT 1 (2275 2850);
DOT 1 (2275 2900);
DOT 1 (2275 2950);
DOT 1 (2275 3000);
DOT 1 (2275 3050);
DOT 1 (2275 3100);
DOT 1 (2275 3200);
DOT 1 (2275 3150);
DOT 1 (2275 3250);
DOT 1 (2275 3300);
DOT 1 (2275 3350);
DOT 1 (2275 3400);
DOT 1 (2275 3450);
DOT 1 (2275 3500);
DOT 1 (2275 3550);
DOT 1 (2275 3600);
DOT 1 (2275 3650);
DOT 1 (2275 3700);
DOT 1 (2275 3750);
DOT 1 (5175 100);
DOT 1 (5175 250);
DOT 1 (5175 200);
DOT 1 (5175 150);
DOT 1 (5175 300);
DOT 1 (5175 350);
DOT 1 (5175 500);
DOT 1 (5175 450);
DOT 1 (5175 400);
DOT 1 (5175 600);
DOT 1 (5175 550);
DOT 1 (5175 650);
DOT 1 (5175 750);
DOT 1 (5175 700);
DOT 1 (5175 850);
DOT 1 (5175 800);
DOT 1 (5175 900);
DOT 1 (5175 1000);
DOT 1 (5175 950);
DOT 1 (5175 1150);
DOT 1 (5175 1100);
DOT 1 (5175 1050);
DOT 1 (5175 1250);
DOT 1 (5175 1200);
DOT 1 (5175 1400);
DOT 1 (5175 1350);
DOT 1 (5175 1300);
DOT 1 (5175 1450);
DOT 1 (5175 1500);
DOT 1 (5175 1550);
DOT 1 (5175 1600);
DOT 1 (5175 1650);
DOT 1 (5175 1750);
DOT 1 (5175 1700);
DOT 1 (5175 1800);
DOT 1 (5175 1900);
DOT 1 (5175 1850);
DOT 1 (5175 2000);
DOT 1 (5175 1950);
DOT 1 (5175 2050);
DOT 1 (5175 2150);
DOT 1 (5175 2100);
DOT 1 (5175 2300);
DOT 1 (5175 2250);
DOT 1 (5175 2200);
DOT 1 (5175 2400);
DOT 1 (5175 2350);
DOT 1 (5175 2550);
DOT 1 (5175 2500);
DOT 1 (5175 2450);
DOT 1 (5175 2650);
DOT 1 (5175 2600);
DOT 1 (5175 2700);
DOT 1 (5175 2800);
DOT 1 (5175 2750);
DOT 1 (5175 2900);
DOT 1 (5175 2850);
DOT 1 (5175 2950);
DOT 1 (5175 3050);
DOT 1 (5175 3000);
DOT 1 (5175 3100);
DOT 1 (5175 3150);
DOT 1 (5175 3200);
DOT 1 (5175 3300);
DOT 1 (5175 3250);
DOT 1 (5175 3450);
DOT 1 (5175 3400);
DOT 1 (5175 3350);
DOT 1 (5175 3500);
DOT 1 (5175 3550);
DOT 1 (5175 3700);
DOT 1 (5175 3650);
DOT 1 (5175 3600);
DOT 1 (5175 3750);
DOT 1 (-2100 2300);
QUIT
